FILE_TYPE = MACRO_DRAWING;
SET COLOR_WIRE YELLOW;
SET COLOR_PROP ORANGE;
SET COLOR_DOT WHITE;
SET COLOR_ARC YELLOW;
SET COLOR_BODY GREEN;
SET COLOR_NOTE PURPLE;
SET PROP_DISPLAY VALUE;
SET PAGE_NUMBER P398;
FORCEADD P1V0..1
(-8425 5575);
FORCEPROP 3 LASTPIN (-8425 5525) SIG_NAME P1V8_CPU1_RT_1D\g
J 0
(-8415 5535);
DISPLAY 0.659574 (-8415 5535);
PAINT MONO (-8415 5535);
DISPLAY INVISIBLE (-8415 5535);
FORCEPROP 1 LAST HDL_POWER P1V8_CPU1_RT_1D
J 1
(-8425 5625);
DISPLAY 0.489362 (-8425 5625);
PAINT SKYBLUE (-8425 5625);
FORCEPROP 2 LAST CDS_LIB pure_quanta_power
J 0
(-8425 5575);
DISPLAY INVISIBLE (-8425 5575);
FORCEPROP 1 LAST PATH I1
J 0
(-8375 5600);
DISPLAY 0.872340 (-8375 5600);
PAINT AQUA (-8375 5600);
DISPLAY INVISIBLE (-8375 5600);
FORCEADD UNIVERSAL_GND..1
(-6425 4150);
FORCEPROP 3 LASTPIN (-6425 4200) SIG_NAME GND\g
J 0
(-6415 4210);
DISPLAY 0.659574 (-6415 4210);
PAINT MONO (-6415 4210);
DISPLAY INVISIBLE (-6415 4210);
FORCEPROP 2 LAST CDS_LIB pure_quanta_power
J 0
(-6425 4150);
DISPLAY INVISIBLE (-6425 4150);
FORCEPROP 1 LAST HDL_POWER GND
J 1
(-6400 4075);
DISPLAY 0.872340 (-6400 4075);
PAINT GREEN (-6400 4075);
DISPLAY INVISIBLE (-6400 4075);
FORCEPROP 1 LAST PATH I10
J 0
(-6350 4150);
DISPLAY 0.872340 (-6350 4150);
PAINT AQUA (-6350 4150);
DISPLAY INVISIBLE (-6350 4150);
FORCEADD Q_CAP..1
(-2500 1425);
FORCEPROP 1 LAST LOCATION C201
J 0
(-2450 1525);
DISPLAY 0.978723 (-2450 1525);
PAINT WHITE (-2450 1525);
FORCEPROP 0 LAST $SEC 1
J 0
(-2450 1575);
DISPLAY 0.680851 (-2450 1575);
PAINT MONO (-2450 1575);
DISPLAY INVISIBLE (-2450 1575);
FORCEPROP 0 LAST CDS_SEC 1
J 0
(-2450 1575);
DISPLAY 0.680851 (-2450 1575);
DISPLAY INVISIBLE (-2450 1575);
FORCEPROP 1 LASTPIN (-2500 1525) $PN 1
J 0
(-2490 1505);
DISPLAY 0.787234 (-2490 1505);
PAINT MONO (-2490 1505);
FORCEPROP 1 LASTPIN (-2500 1325) $PN 2
J 0
(-2490 1305);
DISPLAY 0.787234 (-2490 1305);
PAINT MONO (-2490 1305);
FORCEPROP 1 LAST VALUE 1UF
J 0
(-2450 1475);
DISPLAY 0.510638 (-2450 1475);
FORCEPROP 1 LAST VOLTAGE 4V
J 0
(-2450 1425);
DISPLAY 0.510638 (-2450 1425);
FORCEPROP 1 LAST PACK_TYPE 0201
J 0
(-2450 1275);
DISPLAY 0.510638 (-2450 1275);
FORCEPROP 1 LAST MATERIAL X6S
J 0
(-2450 1325);
DISPLAY 0.510638 (-2450 1325);
FORCEPROP 1 LAST TOLERANCE 20%
J 0
(-2450 1375);
DISPLAY 0.510638 (-2450 1375);
FORCEPROP 2 LAST CDS_LIB pure_quanta
J 0
(-2500 1425);
DISPLAY INVISIBLE (-2500 1425);
FORCEPROP 1 LAST PATH I100
J 0
(-2450 1575);
DISPLAY 0.978723 (-2450 1575);
PAINT WHITE (-2450 1575);
DISPLAY INVISIBLE (-2450 1575);
FORCEPROP 1 LAST PART_NUMBER CH-10KMEE00
J 0
(-2450 1275);
DISPLAY 0.510638 (-2450 1275);
DISPLAY INVISIBLE (-2450 1275);
FORCEADD Q_CAP..1
(-2125 3200);
FORCEPROP 1 LAST LOCATION C281
J 0
(-2075 3300);
DISPLAY 0.978723 (-2075 3300);
PAINT WHITE (-2075 3300);
FORCEPROP 0 LAST $SEC 1
J 0
(-2075 3350);
DISPLAY 0.680851 (-2075 3350);
PAINT MONO (-2075 3350);
DISPLAY INVISIBLE (-2075 3350);
FORCEPROP 0 LAST CDS_SEC 1
J 0
(-2075 3350);
DISPLAY 0.680851 (-2075 3350);
DISPLAY INVISIBLE (-2075 3350);
FORCEPROP 1 LASTPIN (-2125 3300) $PN 1
J 0
(-2115 3280);
DISPLAY 0.787234 (-2115 3280);
PAINT MONO (-2115 3280);
FORCEPROP 1 LASTPIN (-2125 3100) $PN 2
J 0
(-2115 3080);
DISPLAY 0.787234 (-2115 3080);
PAINT MONO (-2115 3080);
FORCEPROP 1 LAST TOLERANCE 10%
J 0
(-2075 3150);
DISPLAY 0.638298 (-2075 3150);
FORCEPROP 1 LAST PACK_TYPE C0201
J 0
(-2075 3050);
DISPLAY 0.638298 (-2075 3050);
FORCEPROP 1 LAST MATERIAL X7S
J 0
(-2075 3100);
DISPLAY 0.638298 (-2075 3100);
FORCEPROP 1 LAST VALUE 0.1UF
J 0
(-2075 3250);
DISPLAY 0.638298 (-2075 3250);
FORCEPROP 1 LAST VOLTAGE 10V
J 0
(-2075 3200);
DISPLAY 0.638298 (-2075 3200);
FORCEPROP 2 LAST CDS_LIB pure_quanta
J 0
(-2125 3200);
DISPLAY INVISIBLE (-2125 3200);
FORCEPROP 1 LAST PATH I101
J 0
(-2075 3350);
DISPLAY 0.978723 (-2075 3350);
PAINT WHITE (-2075 3350);
DISPLAY INVISIBLE (-2075 3350);
FORCEPROP 1 LAST PART_NUMBER CH4102K6E00
J 0
(-2075 3050);
DISPLAY 0.978723 (-2075 3050);
DISPLAY INVISIBLE (-2075 3050);
FORCEADD Q_CAP..1
(-1875 3200);
FORCEPROP 1 LAST LOCATION C283
J 0
(-1825 3300);
DISPLAY 0.978723 (-1825 3300);
PAINT WHITE (-1825 3300);
FORCEPROP 0 LAST $SEC 1
J 0
(-1825 3350);
DISPLAY 0.680851 (-1825 3350);
PAINT MONO (-1825 3350);
DISPLAY INVISIBLE (-1825 3350);
FORCEPROP 0 LAST CDS_SEC 1
J 0
(-1825 3350);
DISPLAY 0.680851 (-1825 3350);
DISPLAY INVISIBLE (-1825 3350);
FORCEPROP 1 LASTPIN (-1875 3300) $PN 1
J 0
(-1865 3280);
DISPLAY 0.787234 (-1865 3280);
PAINT MONO (-1865 3280);
FORCEPROP 1 LASTPIN (-1875 3100) $PN 2
J 0
(-1865 3080);
DISPLAY 0.787234 (-1865 3080);
PAINT MONO (-1865 3080);
FORCEPROP 1 LAST MATERIAL X7S
J 0
(-1825 3100);
DISPLAY 0.638298 (-1825 3100);
FORCEPROP 1 LAST PACK_TYPE C0201
J 0
(-1825 3050);
DISPLAY 0.638298 (-1825 3050);
FORCEPROP 1 LAST VOLTAGE 10V
J 0
(-1825 3200);
DISPLAY 0.638298 (-1825 3200);
FORCEPROP 1 LAST VALUE 0.1UF
J 0
(-1825 3250);
DISPLAY 0.638298 (-1825 3250);
FORCEPROP 1 LAST TOLERANCE 10%
J 0
(-1825 3150);
DISPLAY 0.638298 (-1825 3150);
FORCEPROP 2 LAST CDS_LIB pure_quanta
J 0
(-1875 3200);
DISPLAY INVISIBLE (-1875 3200);
FORCEPROP 1 LAST PATH I102
J 0
(-1825 3350);
DISPLAY 0.978723 (-1825 3350);
PAINT WHITE (-1825 3350);
DISPLAY INVISIBLE (-1825 3350);
FORCEPROP 1 LAST PART_NUMBER CH4102K6E00
J 0
(-1825 3050);
DISPLAY 0.978723 (-1825 3050);
DISPLAY INVISIBLE (-1825 3050);
FORCEADD Q_CAPP..1
(-1350 2550);
FORCEPROP 1 LAST LOCATION C7020
J 0
(-1300 2650);
DISPLAY 0.787234 (-1300 2650);
FORCEPROP 0 LAST $SEC 1
J 0
(-1300 2700);
DISPLAY 0.680851 (-1300 2700);
PAINT MONO (-1300 2700);
DISPLAY INVISIBLE (-1300 2700);
FORCEPROP 0 LAST CDS_SEC 1
J 0
(-1300 2700);
DISPLAY 0.680851 (-1300 2700);
DISPLAY INVISIBLE (-1300 2700);
FORCEPROP 1 LASTPIN (-1350 2650) $PN 1
J 0
(-1340 2635);
DISPLAY 0.787234 (-1340 2635);
PAINT MONO (-1340 2635);
FORCEPROP 1 LASTPIN (-1350 2450) $PN 2
J 0
(-1340 2435);
DISPLAY 0.787234 (-1340 2435);
PAINT MONO (-1340 2435);
FORCEPROP 1 LAST MATERIAL SPCAP
J 0
(-1300 2450);
DISPLAY 0.510638 (-1300 2450);
FORCEPROP 1 LAST VOLTAGE 2.5V
J 0
(-1300 2500);
DISPLAY 0.510638 (-1300 2500);
FORCEPROP 1 LAST PACK_TYPE SMLF
J 0
(-1300 2400);
DISPLAY 0.510638 (-1300 2400);
FORCEPROP 1 LAST TOLERANCE 20%
J 0
(-1300 2550);
DISPLAY 0.510638 (-1300 2550);
FORCEPROP 1 LAST VALUE 470UF
J 0
(-1300 2600);
DISPLAY 0.510638 (-1300 2600);
FORCEPROP 2 LAST CDS_LIB pure_quanta
J 0
(-1350 2550);
DISPLAY INVISIBLE (-1350 2550);
FORCEPROP 1 LAST PATH I103
J 0
(-1300 2700);
DISPLAY 0.978723 (-1300 2700);
DISPLAY INVISIBLE (-1300 2700);
FORCEPROP 1 LAST PART_NUMBER CH747LM8818
J 0
(-1300 2350);
DISPLAY 0.404255 (-1300 2350);
DISPLAY INVISIBLE (-1300 2350);
FORCEADD Q_CAPP..1
(-1050 2550);
FORCEPROP 1 LAST LOCATION C7021
J 0
(-1000 2650);
DISPLAY 0.787234 (-1000 2650);
FORCEPROP 0 LAST $SEC 1
J 0
(-1000 2700);
DISPLAY 0.680851 (-1000 2700);
PAINT MONO (-1000 2700);
DISPLAY INVISIBLE (-1000 2700);
FORCEPROP 0 LAST CDS_SEC 1
J 0
(-1000 2700);
DISPLAY 0.680851 (-1000 2700);
DISPLAY INVISIBLE (-1000 2700);
FORCEPROP 1 LASTPIN (-1050 2650) $PN 1
J 0
(-1040 2635);
DISPLAY 0.787234 (-1040 2635);
PAINT MONO (-1040 2635);
FORCEPROP 1 LASTPIN (-1050 2450) $PN 2
J 0
(-1040 2435);
DISPLAY 0.787234 (-1040 2435);
PAINT MONO (-1040 2435);
FORCEPROP 1 LAST VALUE 470UF
J 0
(-1000 2600);
DISPLAY 0.510638 (-1000 2600);
FORCEPROP 1 LAST TOLERANCE 20%
J 0
(-1000 2550);
DISPLAY 0.510638 (-1000 2550);
FORCEPROP 1 LAST MATERIAL SPCAP
J 0
(-1000 2450);
DISPLAY 0.510638 (-1000 2450);
FORCEPROP 1 LAST PACK_TYPE SMLF
J 0
(-1000 2400);
DISPLAY 0.510638 (-1000 2400);
FORCEPROP 1 LAST VOLTAGE 2.5V
J 0
(-1000 2500);
DISPLAY 0.510638 (-1000 2500);
FORCEPROP 2 LAST CDS_LIB pure_quanta
J 0
(-1050 2550);
DISPLAY INVISIBLE (-1050 2550);
FORCEPROP 1 LAST PATH I104
J 0
(-1000 2700);
DISPLAY 0.978723 (-1000 2700);
DISPLAY INVISIBLE (-1000 2700);
FORCEPROP 1 LAST PART_NUMBER CH747LM8818
J 0
(-1000 2350);
DISPLAY 0.404255 (-1000 2350);
DISPLAY INVISIBLE (-1000 2350);
FORCEADD Q_CAP..1
(-750 2550);
FORCEPROP 1 LAST LOCATION C7022
J 0
(-700 2650);
DISPLAY 0.638298 (-700 2650);
FORCEPROP 0 LAST $SEC 1
J 0
(-700 2700);
DISPLAY 0.680851 (-700 2700);
PAINT MONO (-700 2700);
DISPLAY INVISIBLE (-700 2700);
FORCEPROP 0 LAST CDS_SEC 1
J 0
(-700 2700);
DISPLAY 0.680851 (-700 2700);
DISPLAY INVISIBLE (-700 2700);
FORCEPROP 1 LASTPIN (-750 2650) $PN 1
J 0
(-740 2630);
DISPLAY 0.787234 (-740 2630);
PAINT MONO (-740 2630);
FORCEPROP 1 LASTPIN (-750 2450) $PN 2
J 0
(-740 2430);
DISPLAY 0.787234 (-740 2430);
PAINT MONO (-740 2430);
FORCEPROP 1 LAST TOLERANCE 20%
J 0
(-700 2500);
DISPLAY 0.638298 (-700 2500);
FORCEPROP 1 LAST MATERIAL X6S
J 0
(-700 2450);
DISPLAY 0.638298 (-700 2450);
FORCEPROP 1 LAST PACK_TYPE C0805
J 0
(-700 2350);
DISPLAY 0.638298 (-700 2350);
FORCEPROP 1 LAST VALUE 100UF
J 0
(-700 2600);
DISPLAY 0.638298 (-700 2600);
FORCEPROP 1 LAST VOLTAGE 4V
J 0
(-700 2550);
DISPLAY 0.638298 (-700 2550);
FORCEPROP 2 LAST CDS_LIB pure_quanta
J 0
(-750 2550);
DISPLAY INVISIBLE (-750 2550);
FORCEPROP 1 LAST PATH I105
J 0
(-700 2700);
DISPLAY 0.978723 (-700 2700);
PAINT WHITE (-700 2700);
DISPLAY INVISIBLE (-700 2700);
FORCEPROP 1 LAST PART_NUMBER CH710KMEA01
J 0
(-700 2400);
DISPLAY 0.638298 (-700 2400);
DISPLAY INVISIBLE (-700 2400);
FORCEADD Q_CAP..1
(-7325 5300);
FORCEPROP 1 LAST LOCATION C113
J 0
(-7275 5400);
DISPLAY 0.638298 (-7275 5400);
PAINT WHITE (-7275 5400);
FORCEPROP 0 LAST $SEC 1
J 0
(-7275 5450);
DISPLAY 0.680851 (-7275 5450);
PAINT MONO (-7275 5450);
DISPLAY INVISIBLE (-7275 5450);
FORCEPROP 0 LAST CDS_SEC 1
J 0
(-7275 5450);
DISPLAY 0.680851 (-7275 5450);
DISPLAY INVISIBLE (-7275 5450);
FORCEPROP 1 LASTPIN (-7325 5400) $PN 1
J 0
(-7315 5380);
DISPLAY 0.787234 (-7315 5380);
PAINT MONO (-7315 5380);
FORCEPROP 1 LASTPIN (-7325 5200) $PN 2
J 0
(-7315 5180);
DISPLAY 0.787234 (-7315 5180);
PAINT MONO (-7315 5180);
FORCEPROP 1 LAST PACK_TYPE C0805
J 0
(-7275 5150);
DISPLAY 0.510638 (-7275 5150);
FORCEPROP 1 LAST VOLTAGE 4V
J 0
(-7275 5300);
DISPLAY 0.510638 (-7275 5300);
FORCEPROP 1 LAST MATERIAL X6S
J 0
(-7275 5200);
DISPLAY 0.510638 (-7275 5200);
FORCEPROP 1 LAST VALUE 100UF
J 0
(-7275 5350);
DISPLAY 0.510638 (-7275 5350);
FORCEPROP 1 LAST TOLERANCE 20%
J 0
(-7275 5250);
DISPLAY 0.510638 (-7275 5250);
FORCEPROP 2 LAST CDS_LIB pure_quanta
J 0
(-7325 5300);
DISPLAY INVISIBLE (-7325 5300);
FORCEPROP 1 LAST PATH I12
J 0
(-7275 5450);
DISPLAY 0.978723 (-7275 5450);
PAINT WHITE (-7275 5450);
DISPLAY INVISIBLE (-7275 5450);
FORCEPROP 1 LAST PART_NUMBER CH710KMEA01
J 0
(-7275 5150);
DISPLAY 0.404255 (-7275 5150);
DISPLAY INVISIBLE (-7275 5150);
FORCEADD Q_CAP..1
(-6825 5275);
FORCEPROP 1 LAST LOCATION C118
J 0
(-6775 5375);
DISPLAY 0.638298 (-6775 5375);
PAINT WHITE (-6775 5375);
FORCEPROP 0 LAST $SEC 1
J 0
(-6775 5425);
DISPLAY 0.680851 (-6775 5425);
PAINT MONO (-6775 5425);
DISPLAY INVISIBLE (-6775 5425);
FORCEPROP 0 LAST CDS_SEC 1
J 0
(-6775 5425);
DISPLAY 0.680851 (-6775 5425);
DISPLAY INVISIBLE (-6775 5425);
FORCEPROP 1 LASTPIN (-6825 5375) $PN 1
J 0
(-6815 5355);
DISPLAY 0.787234 (-6815 5355);
PAINT MONO (-6815 5355);
FORCEPROP 1 LASTPIN (-6825 5175) $PN 2
J 0
(-6815 5155);
DISPLAY 0.787234 (-6815 5155);
PAINT MONO (-6815 5155);
FORCEPROP 1 LAST VALUE 10UF
J 0
(-6775 5325);
DISPLAY 0.510638 (-6775 5325);
FORCEPROP 1 LAST TOLERANCE 20%
J 0
(-6775 5225);
DISPLAY 0.510638 (-6775 5225);
FORCEPROP 1 LAST MATERIAL X6S
J 0
(-6775 5175);
DISPLAY 0.510638 (-6775 5175);
FORCEPROP 1 LAST VOLTAGE 6.3V
J 0
(-6775 5275);
DISPLAY 0.510638 (-6775 5275);
FORCEPROP 1 LAST PACK_TYPE C0402
J 0
(-6775 5125);
DISPLAY 0.510638 (-6775 5125);
FORCEPROP 2 LAST CDS_LIB pure_quanta
J 0
(-6825 5275);
DISPLAY INVISIBLE (-6825 5275);
FORCEPROP 1 LAST PATH I14
J 0
(-6775 5425);
DISPLAY 0.978723 (-6775 5425);
PAINT WHITE (-6775 5425);
DISPLAY INVISIBLE (-6775 5425);
FORCEPROP 1 LAST PART_NUMBER CH6101MEB01
J 0
(-6775 5125);
DISPLAY 0.978723 (-6775 5125);
DISPLAY INVISIBLE (-6775 5125);
FORCEADD Q_CAP..1
(-6575 5275);
FORCEPROP 1 LAST LOCATION C122
J 0
(-6525 5375);
DISPLAY 0.638298 (-6525 5375);
PAINT WHITE (-6525 5375);
FORCEPROP 0 LAST $SEC 1
J 0
(-6525 5425);
DISPLAY 0.680851 (-6525 5425);
PAINT MONO (-6525 5425);
DISPLAY INVISIBLE (-6525 5425);
FORCEPROP 0 LAST CDS_SEC 1
J 0
(-6525 5425);
DISPLAY 0.680851 (-6525 5425);
DISPLAY INVISIBLE (-6525 5425);
FORCEPROP 1 LASTPIN (-6575 5375) $PN 1
J 0
(-6565 5355);
DISPLAY 0.787234 (-6565 5355);
PAINT MONO (-6565 5355);
FORCEPROP 1 LASTPIN (-6575 5175) $PN 2
J 0
(-6565 5155);
DISPLAY 0.787234 (-6565 5155);
PAINT MONO (-6565 5155);
FORCEPROP 1 LAST VOLTAGE 6.3V
J 0
(-6525 5275);
DISPLAY 0.510638 (-6525 5275);
FORCEPROP 1 LAST VALUE 4.7UF
J 0
(-6525 5325);
DISPLAY 0.510638 (-6525 5325);
FORCEPROP 1 LAST TOLERANCE 20%
J 0
(-6525 5225);
DISPLAY 0.510638 (-6525 5225);
FORCEPROP 1 LAST MATERIAL X6S
J 0
(-6525 5175);
DISPLAY 0.510638 (-6525 5175);
FORCEPROP 1 LAST PACK_TYPE 0402
J 0
(-6525 5125);
DISPLAY 0.510638 (-6525 5125);
FORCEPROP 2 LAST CDS_LIB pure_quanta
J 0
(-6575 5275);
DISPLAY INVISIBLE (-6575 5275);
FORCEPROP 1 LAST PATH I15
J 0
(-6525 5425);
DISPLAY 0.978723 (-6525 5425);
PAINT WHITE (-6525 5425);
DISPLAY INVISIBLE (-6525 5425);
FORCEPROP 1 LAST PART_NUMBER CH5471MEB01
J 0
(-6525 5125);
DISPLAY 0.978723 (-6525 5125);
DISPLAY INVISIBLE (-6525 5125);
FORCEADD UNIVERSAL_GND..1
(-6650 5000);
FORCEPROP 3 LASTPIN (-6650 5050) SIG_NAME GND\g
J 0
(-6640 5060);
DISPLAY 0.659574 (-6640 5060);
PAINT MONO (-6640 5060);
DISPLAY INVISIBLE (-6640 5060);
FORCEPROP 2 LAST CDS_LIB pure_quanta_power
J 0
(-6650 5000);
DISPLAY INVISIBLE (-6650 5000);
FORCEPROP 1 LAST HDL_POWER GND
J 1
(-6625 4925);
DISPLAY 0.872340 (-6625 4925);
PAINT GREEN (-6625 4925);
DISPLAY INVISIBLE (-6625 4925);
FORCEPROP 1 LAST PATH I17
J 0
(-6575 5000);
DISPLAY 0.872340 (-6575 5000);
PAINT AQUA (-6575 5000);
DISPLAY INVISIBLE (-6575 5000);
FORCEADD Q_CAP..1
(-6625 4475);
FORCEPROP 1 LAST LOCATION C123
J 0
(-6575 4575);
DISPLAY 0.808511 (-6575 4575);
PAINT WHITE (-6575 4575);
FORCEPROP 0 LAST $SEC 1
J 0
(-6575 4625);
DISPLAY 0.680851 (-6575 4625);
PAINT MONO (-6575 4625);
DISPLAY INVISIBLE (-6575 4625);
FORCEPROP 0 LAST CDS_SEC 1
J 0
(-6575 4625);
DISPLAY 0.680851 (-6575 4625);
DISPLAY INVISIBLE (-6575 4625);
FORCEPROP 1 LASTPIN (-6625 4575) $PN 1
J 0
(-6615 4555);
DISPLAY 0.787234 (-6615 4555);
PAINT MONO (-6615 4555);
FORCEPROP 1 LASTPIN (-6625 4375) $PN 2
J 0
(-6615 4355);
DISPLAY 0.787234 (-6615 4355);
PAINT MONO (-6615 4355);
FORCEPROP 1 LAST PACK_TYPE 0201
J 0
(-6575 4325);
DISPLAY 0.510638 (-6575 4325);
FORCEPROP 1 LAST TOLERANCE 20%
J 0
(-6575 4425);
DISPLAY 0.510638 (-6575 4425);
FORCEPROP 1 LAST VALUE 1UF
J 0
(-6575 4525);
DISPLAY 0.510638 (-6575 4525);
FORCEPROP 1 LAST MATERIAL X6S
J 0
(-6575 4375);
DISPLAY 0.510638 (-6575 4375);
FORCEPROP 1 LAST VOLTAGE 4V
J 0
(-6575 4475);
DISPLAY 0.510638 (-6575 4475);
FORCEPROP 2 LAST CDS_LIB pure_quanta
J 0
(-6625 4475);
DISPLAY INVISIBLE (-6625 4475);
FORCEPROP 1 LAST PATH I18
J 0
(-6575 4625);
DISPLAY 0.978723 (-6575 4625);
PAINT WHITE (-6575 4625);
DISPLAY INVISIBLE (-6575 4625);
FORCEPROP 1 LAST PART_NUMBER CH-10KMEE00
J 0
(-6575 4325);
DISPLAY 0.510638 (-6575 4325);
DISPLAY INVISIBLE (-6575 4325);
FORCEADD Q_CAP..1
(-7050 3400);
FORCEPROP 1 LAST LOCATION C125
J 0
(-7000 3500);
DISPLAY 0.638298 (-7000 3500);
PAINT WHITE (-7000 3500);
FORCEPROP 0 LAST $SEC 1
J 0
(-7000 3550);
DISPLAY 0.680851 (-7000 3550);
PAINT MONO (-7000 3550);
DISPLAY INVISIBLE (-7000 3550);
FORCEPROP 0 LAST CDS_SEC 1
J 0
(-7000 3550);
DISPLAY 0.680851 (-7000 3550);
DISPLAY INVISIBLE (-7000 3550);
FORCEPROP 1 LASTPIN (-7050 3500) $PN 1
J 0
(-7040 3480);
DISPLAY 0.787234 (-7040 3480);
PAINT MONO (-7040 3480);
FORCEPROP 1 LASTPIN (-7050 3300) $PN 2
J 0
(-7040 3280);
DISPLAY 0.787234 (-7040 3280);
PAINT MONO (-7040 3280);
FORCEPROP 1 LAST VOLTAGE 4V
J 0
(-7000 3400);
DISPLAY 0.510638 (-7000 3400);
FORCEPROP 1 LAST TOLERANCE 20%
J 0
(-7000 3350);
DISPLAY 0.510638 (-7000 3350);
FORCEPROP 1 LAST VALUE 1UF
J 0
(-7000 3450);
DISPLAY 0.510638 (-7000 3450);
FORCEPROP 1 LAST MATERIAL X6S
J 0
(-7000 3300);
DISPLAY 0.510638 (-7000 3300);
FORCEPROP 1 LAST PACK_TYPE 0201
J 0
(-7000 3250);
DISPLAY 0.510638 (-7000 3250);
FORCEPROP 2 LAST CDS_LIB pure_quanta
J 0
(-7050 3400);
DISPLAY INVISIBLE (-7050 3400);
FORCEPROP 1 LAST PATH I19
J 0
(-7000 3550);
DISPLAY 0.978723 (-7000 3550);
PAINT WHITE (-7000 3550);
DISPLAY INVISIBLE (-7000 3550);
FORCEPROP 1 LAST PART_NUMBER CH-10KMEE00
J 0
(-7000 3250);
DISPLAY 0.510638 (-7000 3250);
DISPLAY INVISIBLE (-7000 3250);
FORCEADD Q_CAP..1
(-7050 4475);
FORCEPROP 1 LAST LOCATION C119
J 0
(-7000 4575);
DISPLAY 0.808511 (-7000 4575);
PAINT WHITE (-7000 4575);
FORCEPROP 0 LAST $SEC 1
J 0
(-7000 4625);
DISPLAY 0.680851 (-7000 4625);
PAINT MONO (-7000 4625);
DISPLAY INVISIBLE (-7000 4625);
FORCEPROP 0 LAST CDS_SEC 1
J 0
(-7000 4625);
DISPLAY 0.680851 (-7000 4625);
DISPLAY INVISIBLE (-7000 4625);
FORCEPROP 1 LASTPIN (-7050 4575) $PN 1
J 0
(-7040 4555);
DISPLAY 0.787234 (-7040 4555);
PAINT MONO (-7040 4555);
FORCEPROP 1 LASTPIN (-7050 4375) $PN 2
J 0
(-7040 4355);
DISPLAY 0.787234 (-7040 4355);
PAINT MONO (-7040 4355);
FORCEPROP 1 LAST MATERIAL X6S
J 0
(-7000 4375);
DISPLAY 0.510638 (-7000 4375);
FORCEPROP 1 LAST TOLERANCE 20%
J 0
(-7000 4425);
DISPLAY 0.510638 (-7000 4425);
FORCEPROP 1 LAST PACK_TYPE C0402
J 0
(-7000 4325);
DISPLAY 0.510638 (-7000 4325);
FORCEPROP 1 LAST VALUE 10UF
J 0
(-7000 4525);
DISPLAY 0.510638 (-7000 4525);
FORCEPROP 1 LAST VOLTAGE 6.3V
J 0
(-7000 4475);
DISPLAY 0.510638 (-7000 4475);
FORCEPROP 2 LAST CDS_LIB pure_quanta
J 0
(-7050 4475);
DISPLAY INVISIBLE (-7050 4475);
FORCEPROP 1 LAST PATH I20
J 0
(-7000 4625);
DISPLAY 0.978723 (-7000 4625);
PAINT WHITE (-7000 4625);
DISPLAY INVISIBLE (-7000 4625);
FORCEPROP 1 LAST PART_NUMBER CH6101MEB01
J 0
(-7000 4325);
DISPLAY 0.978723 (-7000 4325);
DISPLAY INVISIBLE (-7000 4325);
FORCEADD Q_CAP..1
(-7075 5300);
FORCEPROP 1 LAST LOCATION C115
J 0
(-7025 5400);
DISPLAY 0.510638 (-7025 5400);
PAINT WHITE (-7025 5400);
FORCEPROP 0 LAST $SEC 1
J 0
(-7025 5425);
DISPLAY 0.680851 (-7025 5425);
PAINT MONO (-7025 5425);
DISPLAY INVISIBLE (-7025 5425);
FORCEPROP 0 LAST CDS_SEC 1
J 0
(-7025 5425);
DISPLAY 0.680851 (-7025 5425);
DISPLAY INVISIBLE (-7025 5425);
FORCEPROP 1 LASTPIN (-7075 5400) $PN 1
J 0
(-7065 5380);
DISPLAY 0.787234 (-7065 5380);
PAINT MONO (-7065 5380);
FORCEPROP 1 LASTPIN (-7075 5200) $PN 2
J 0
(-7065 5180);
DISPLAY 0.787234 (-7065 5180);
PAINT MONO (-7065 5180);
FORCEPROP 1 LAST VALUE 22UF
J 0
(-7025 5350);
DISPLAY 0.510638 (-7025 5350);
FORCEPROP 1 LAST MATERIAL X6S
J 0
(-7025 5200);
DISPLAY 0.510638 (-7025 5200);
FORCEPROP 1 LAST PACK_TYPE C0402
J 0
(-7025 5150);
DISPLAY 0.510638 (-7025 5150);
FORCEPROP 1 LAST VOLTAGE 4V
J 0
(-7025 5300);
DISPLAY 0.510638 (-7025 5300);
FORCEPROP 1 LAST TOLERANCE 20%
J 0
(-7025 5250);
DISPLAY 0.510638 (-7025 5250);
FORCEPROP 2 LAST CDS_LIB pure_quanta
J 0
(-7075 5300);
DISPLAY INVISIBLE (-7075 5300);
FORCEPROP 1 LAST PATH I21
J 0
(-7025 5450);
DISPLAY 0.978723 (-7025 5450);
PAINT WHITE (-7025 5450);
DISPLAY INVISIBLE (-7025 5450);
FORCEPROP 1 LAST PART_NUMBER CH622KMEB02
J 0
(-7025 5150);
DISPLAY 0.978723 (-7025 5150);
DISPLAY INVISIBLE (-7025 5150);
FORCEADD Q_INDUCTOR..1
(-8050 4750);
FORCEPROP 1 LAST LOCATION L3
J 0
(-8175 4910);
DISPLAY 0.723404 (-8175 4910);
PAINT GREEN (-8175 4910);
FORCEPROP 0 LAST $SEC 1
J 0
(-8175 5000);
DISPLAY 0.680851 (-8175 5000);
PAINT MONO (-8175 5000);
DISPLAY INVISIBLE (-8175 5000);
FORCEPROP 0 LAST CDS_SEC 1
J 0
(-8175 5000);
DISPLAY 0.680851 (-8175 5000);
DISPLAY INVISIBLE (-8175 5000);
FORCEPROP 0 LASTPIN (-8150 4725) $PN 1
J 2
(-8160 4735);
DISPLAY 0.680851 (-8160 4735);
PAINT MONO (-8160 4735);
FORCEPROP 0 LASTPIN (-7950 4725) $PN 2
J 0
(-7940 4735);
DISPLAY 0.680851 (-7940 4735);
PAINT MONO (-7940 4735);
FORCEPROP 2 LAST VALUE BLM21SN300SN1D/5A
J 0
(-8300 4650);
DISPLAY 0.680851 (-8300 4650);
FORCEPROP 2 LAST PACK_TYPE SMLF
J 0
(-8175 4950);
DISPLAY 0.680851 (-8175 4950);
FORCEPROP 1 LAST MATERIAL IND
J 0
(-8175 4805);
DISPLAY 0.723404 (-8175 4805);
PAINT GREEN (-8175 4805);
FORCEPROP 2 LAST CDS_LIB pure_quanta
J 0
(-8050 4750);
DISPLAY INVISIBLE (-8050 4750);
FORCEPROP 1 LAST NEEDS_NO_SIZE TRUE
J 0
(-8050 4750);
DISPLAY 0.468085 (-8050 4750);
PAINT GREEN (-8050 4750);
DISPLAY INVISIBLE (-8050 4750);
FORCEPROP 1 LAST PATH I22
J 0
(-7975 4805);
DISPLAY 0.723404 (-7975 4805);
PAINT GREEN (-7975 4805);
DISPLAY INVISIBLE (-7975 4805);
FORCEPROP 1 LAST PART_NUMBER CX300SN1000
J 0
(-8175 4860);
DISPLAY 0.723404 (-8175 4860);
PAINT GREEN (-8175 4860);
DISPLAY INVISIBLE (-8175 4860);
FORCEADD Q_CAP..1
(-6200 4475);
FORCEPROP 1 LAST LOCATION C129
J 0
(-6150 4575);
DISPLAY 0.978723 (-6150 4575);
PAINT WHITE (-6150 4575);
FORCEPROP 0 LAST $SEC 1
J 0
(-6150 4625);
DISPLAY 0.680851 (-6150 4625);
PAINT MONO (-6150 4625);
DISPLAY INVISIBLE (-6150 4625);
FORCEPROP 0 LAST CDS_SEC 1
J 0
(-6150 4625);
DISPLAY 0.680851 (-6150 4625);
DISPLAY INVISIBLE (-6150 4625);
FORCEPROP 1 LASTPIN (-6200 4575) $PN 1
J 0
(-6190 4555);
DISPLAY 0.787234 (-6190 4555);
PAINT MONO (-6190 4555);
FORCEPROP 1 LASTPIN (-6200 4375) $PN 2
J 0
(-6190 4355);
DISPLAY 0.787234 (-6190 4355);
PAINT MONO (-6190 4355);
FORCEPROP 1 LAST TOLERANCE 10%
J 0
(-6150 4425);
DISPLAY 0.638298 (-6150 4425);
FORCEPROP 1 LAST VOLTAGE 10V
J 0
(-6150 4475);
DISPLAY 0.638298 (-6150 4475);
FORCEPROP 1 LAST VALUE 0.1UF
J 0
(-6150 4525);
DISPLAY 0.638298 (-6150 4525);
FORCEPROP 1 LAST PACK_TYPE C0201
J 0
(-6150 4325);
DISPLAY 0.638298 (-6150 4325);
FORCEPROP 1 LAST MATERIAL X7S
J 0
(-6150 4375);
DISPLAY 0.638298 (-6150 4375);
FORCEPROP 2 LAST CDS_LIB pure_quanta
J 0
(-6200 4475);
DISPLAY INVISIBLE (-6200 4475);
FORCEPROP 1 LAST PATH I23
J 0
(-6150 4625);
DISPLAY 0.978723 (-6150 4625);
PAINT WHITE (-6150 4625);
DISPLAY INVISIBLE (-6150 4625);
FORCEPROP 1 LAST PART_NUMBER CH4102K6E00
J 0
(-6150 4325);
DISPLAY 0.978723 (-6150 4325);
DISPLAY INVISIBLE (-6150 4325);
FORCEADD Q_CAP..1
(-5950 4475);
FORCEPROP 1 LAST LOCATION C131
J 0
(-5900 4575);
DISPLAY 0.978723 (-5900 4575);
PAINT WHITE (-5900 4575);
FORCEPROP 0 LAST $SEC 1
J 0
(-5900 4625);
DISPLAY 0.680851 (-5900 4625);
PAINT MONO (-5900 4625);
DISPLAY INVISIBLE (-5900 4625);
FORCEPROP 0 LAST CDS_SEC 1
J 0
(-5900 4625);
DISPLAY 0.680851 (-5900 4625);
DISPLAY INVISIBLE (-5900 4625);
FORCEPROP 1 LASTPIN (-5950 4575) $PN 1
J 0
(-5940 4555);
DISPLAY 0.787234 (-5940 4555);
PAINT MONO (-5940 4555);
FORCEPROP 1 LASTPIN (-5950 4375) $PN 2
J 0
(-5940 4355);
DISPLAY 0.787234 (-5940 4355);
PAINT MONO (-5940 4355);
FORCEPROP 1 LAST PACK_TYPE C0201
J 0
(-5900 4325);
DISPLAY 0.638298 (-5900 4325);
FORCEPROP 1 LAST MATERIAL X7S
J 0
(-5900 4375);
DISPLAY 0.638298 (-5900 4375);
FORCEPROP 1 LAST VALUE 0.1UF
J 0
(-5900 4525);
DISPLAY 0.638298 (-5900 4525);
FORCEPROP 1 LAST VOLTAGE 10V
J 0
(-5900 4475);
DISPLAY 0.638298 (-5900 4475);
FORCEPROP 1 LAST TOLERANCE 10%
J 0
(-5900 4425);
DISPLAY 0.638298 (-5900 4425);
FORCEPROP 2 LAST CDS_LIB pure_quanta
J 0
(-5950 4475);
DISPLAY INVISIBLE (-5950 4475);
FORCEPROP 1 LAST PATH I24
J 0
(-5900 4625);
DISPLAY 0.978723 (-5900 4625);
PAINT WHITE (-5900 4625);
DISPLAY INVISIBLE (-5900 4625);
FORCEPROP 1 LAST PART_NUMBER CH4102K6E00
J 0
(-5900 4325);
DISPLAY 0.978723 (-5900 4325);
DISPLAY INVISIBLE (-5900 4325);
FORCEADD Q_CAP..1
(-5700 4475);
FORCEPROP 1 LAST LOCATION C133
J 0
(-5650 4575);
DISPLAY 0.978723 (-5650 4575);
PAINT WHITE (-5650 4575);
FORCEPROP 0 LAST $SEC 1
J 0
(-5650 4625);
DISPLAY 0.680851 (-5650 4625);
PAINT MONO (-5650 4625);
DISPLAY INVISIBLE (-5650 4625);
FORCEPROP 0 LAST CDS_SEC 1
J 0
(-5650 4625);
DISPLAY 0.680851 (-5650 4625);
DISPLAY INVISIBLE (-5650 4625);
FORCEPROP 1 LASTPIN (-5700 4575) $PN 1
J 0
(-5690 4555);
DISPLAY 0.787234 (-5690 4555);
PAINT MONO (-5690 4555);
FORCEPROP 1 LASTPIN (-5700 4375) $PN 2
J 0
(-5690 4355);
DISPLAY 0.787234 (-5690 4355);
PAINT MONO (-5690 4355);
FORCEPROP 1 LAST MATERIAL X7S
J 0
(-5650 4375);
DISPLAY 0.638298 (-5650 4375);
FORCEPROP 1 LAST TOLERANCE 10%
J 0
(-5650 4425);
DISPLAY 0.638298 (-5650 4425);
FORCEPROP 1 LAST VALUE 0.1UF
J 0
(-5650 4525);
DISPLAY 0.638298 (-5650 4525);
FORCEPROP 1 LAST VOLTAGE 10V
J 0
(-5650 4475);
DISPLAY 0.638298 (-5650 4475);
FORCEPROP 1 LAST PACK_TYPE C0201
J 0
(-5650 4325);
DISPLAY 0.638298 (-5650 4325);
FORCEPROP 2 LAST CDS_LIB pure_quanta
J 0
(-5700 4475);
DISPLAY INVISIBLE (-5700 4475);
FORCEPROP 1 LAST PATH I25
J 0
(-5650 4625);
DISPLAY 0.978723 (-5650 4625);
PAINT WHITE (-5650 4625);
DISPLAY INVISIBLE (-5650 4625);
FORCEPROP 1 LAST PART_NUMBER CH4102K6E00
J 0
(-5650 4325);
DISPLAY 0.978723 (-5650 4325);
DISPLAY INVISIBLE (-5650 4325);
FORCEADD Q_CAP..1
(-5425 4475);
FORCEPROP 1 LAST LOCATION C134
J 0
(-5375 4575);
DISPLAY 0.978723 (-5375 4575);
PAINT WHITE (-5375 4575);
FORCEPROP 0 LAST $SEC 1
J 0
(-5375 4625);
DISPLAY 0.680851 (-5375 4625);
PAINT MONO (-5375 4625);
DISPLAY INVISIBLE (-5375 4625);
FORCEPROP 0 LAST CDS_SEC 1
J 0
(-5375 4625);
DISPLAY 0.680851 (-5375 4625);
DISPLAY INVISIBLE (-5375 4625);
FORCEPROP 1 LASTPIN (-5425 4575) $PN 1
J 0
(-5415 4555);
DISPLAY 0.787234 (-5415 4555);
PAINT MONO (-5415 4555);
FORCEPROP 1 LASTPIN (-5425 4375) $PN 2
J 0
(-5415 4355);
DISPLAY 0.787234 (-5415 4355);
PAINT MONO (-5415 4355);
FORCEPROP 1 LAST MATERIAL X7S
J 0
(-5375 4375);
DISPLAY 0.638298 (-5375 4375);
FORCEPROP 1 LAST PACK_TYPE C0201
J 0
(-5375 4325);
DISPLAY 0.638298 (-5375 4325);
FORCEPROP 1 LAST VOLTAGE 10V
J 0
(-5375 4475);
DISPLAY 0.638298 (-5375 4475);
FORCEPROP 1 LAST VALUE 0.1UF
J 0
(-5375 4525);
DISPLAY 0.638298 (-5375 4525);
FORCEPROP 1 LAST TOLERANCE 10%
J 0
(-5375 4425);
DISPLAY 0.638298 (-5375 4425);
FORCEPROP 2 LAST CDS_LIB pure_quanta
J 0
(-5425 4475);
DISPLAY INVISIBLE (-5425 4475);
FORCEPROP 1 LAST PATH I26
J 0
(-5375 4625);
DISPLAY 0.978723 (-5375 4625);
PAINT WHITE (-5375 4625);
DISPLAY INVISIBLE (-5375 4625);
FORCEPROP 1 LAST PART_NUMBER CH4102K6E00
J 0
(-5375 4325);
DISPLAY 0.978723 (-5375 4325);
DISPLAY INVISIBLE (-5375 4325);
FORCEADD Q_CAP..1
(-6775 3375);
FORCEPROP 1 LAST LOCATION C130
J 0
(-6725 3475);
DISPLAY 0.978723 (-6725 3475);
PAINT WHITE (-6725 3475);
FORCEPROP 0 LAST $SEC 1
J 0
(-6725 3525);
DISPLAY 0.680851 (-6725 3525);
PAINT MONO (-6725 3525);
DISPLAY INVISIBLE (-6725 3525);
FORCEPROP 0 LAST CDS_SEC 1
J 0
(-6725 3525);
DISPLAY 0.680851 (-6725 3525);
DISPLAY INVISIBLE (-6725 3525);
FORCEPROP 1 LASTPIN (-6775 3475) $PN 1
J 0
(-6765 3455);
DISPLAY 0.787234 (-6765 3455);
PAINT MONO (-6765 3455);
FORCEPROP 1 LASTPIN (-6775 3275) $PN 2
J 0
(-6765 3255);
DISPLAY 0.787234 (-6765 3255);
PAINT MONO (-6765 3255);
FORCEPROP 1 LAST PACK_TYPE C0201
J 0
(-6725 3225);
DISPLAY 0.638298 (-6725 3225);
FORCEPROP 1 LAST MATERIAL X7S
J 0
(-6725 3275);
DISPLAY 0.638298 (-6725 3275);
FORCEPROP 1 LAST VOLTAGE 10V
J 0
(-6725 3375);
DISPLAY 0.638298 (-6725 3375);
FORCEPROP 1 LAST VALUE 0.1UF
J 0
(-6725 3425);
DISPLAY 0.638298 (-6725 3425);
FORCEPROP 1 LAST TOLERANCE 10%
J 0
(-6725 3325);
DISPLAY 0.638298 (-6725 3325);
FORCEPROP 2 LAST CDS_LIB pure_quanta
J 0
(-6775 3375);
DISPLAY INVISIBLE (-6775 3375);
FORCEPROP 1 LAST PATH I27
J 0
(-6725 3525);
DISPLAY 0.978723 (-6725 3525);
PAINT WHITE (-6725 3525);
DISPLAY INVISIBLE (-6725 3525);
FORCEPROP 1 LAST PART_NUMBER CH4102K6E00
J 0
(-6725 3225);
DISPLAY 0.978723 (-6725 3225);
DISPLAY INVISIBLE (-6725 3225);
FORCEADD UNIVERSAL_GND..1
(-6775 2975);
FORCEPROP 3 LASTPIN (-6775 3025) SIG_NAME GND\g
J 0
(-6765 3035);
DISPLAY 0.659574 (-6765 3035);
PAINT MONO (-6765 3035);
DISPLAY INVISIBLE (-6765 3035);
FORCEPROP 2 LAST CDS_LIB pure_quanta_power
J 0
(-6775 2975);
DISPLAY INVISIBLE (-6775 2975);
FORCEPROP 1 LAST HDL_POWER GND
J 1
(-6750 2900);
DISPLAY 0.872340 (-6750 2900);
PAINT GREEN (-6750 2900);
DISPLAY INVISIBLE (-6750 2900);
FORCEPROP 1 LAST PATH I28
J 0
(-6700 2975);
DISPLAY 0.872340 (-6700 2975);
PAINT AQUA (-6700 2975);
DISPLAY INVISIBLE (-6700 2975);
FORCEADD P1V0..1
(-7175 3775);
FORCEPROP 3 LASTPIN (-7175 3725) SIG_NAME P1V8_CPU1_RT0_1A_1D\g
J 0
(-7165 3735);
DISPLAY 0.659574 (-7165 3735);
PAINT MONO (-7165 3735);
DISPLAY INVISIBLE (-7165 3735);
FORCEPROP 1 LAST HDL_POWER P1V8_CPU1_RT0_1A_1D
J 1
(-7175 3825);
DISPLAY 0.489362 (-7175 3825);
PAINT SKYBLUE (-7175 3825);
FORCEPROP 2 LAST CDS_LIB pure_quanta_power
J 0
(-7175 3775);
DISPLAY INVISIBLE (-7175 3775);
FORCEPROP 1 LAST PATH I29
J 0
(-7125 3800);
DISPLAY 0.872340 (-7125 3800);
PAINT AQUA (-7125 3800);
DISPLAY INVISIBLE (-7125 3800);
FORCEADD P1V0..1
(-7575 4950);
FORCEPROP 3 LASTPIN (-7575 4900) SIG_NAME P1V8_CPU1_RT0_1A\g
J 0
(-7565 4910);
DISPLAY 0.659574 (-7565 4910);
PAINT MONO (-7565 4910);
DISPLAY INVISIBLE (-7565 4910);
FORCEPROP 1 LAST HDL_POWER P1V8_CPU1_RT0_1A
J 1
(-7575 5000);
DISPLAY 0.489362 (-7575 5000);
PAINT SKYBLUE (-7575 5000);
FORCEPROP 2 LAST CDS_LIB pure_quanta_power
J 0
(-7575 4950);
DISPLAY INVISIBLE (-7575 4950);
FORCEPROP 1 LAST PATH I3
J 0
(-7525 4975);
DISPLAY 0.872340 (-7525 4975);
PAINT AQUA (-7525 4975);
DISPLAY INVISIBLE (-7525 4975);
FORCEADD Q_RES..1
(-7975 4050);
FORCEPROP 1 LAST LOCATION R6702
J 0
(-8250 4075);
DISPLAY 0.808511 (-8250 4075);
FORCEPROP 2 LAST SEC 1
J 0
(-8025 4250);
DISPLAY 0.680851 (-8025 4250);
PAINT MONO (-8025 4250);
DISPLAY INVISIBLE (-8025 4250);
FORCEPROP 1 LASTPIN (-8075 4050) $PN 1
J 0
(-8063 4062);
DISPLAY 0.787234 (-8063 4062);
PAINT MONO (-8063 4062);
FORCEPROP 1 LASTPIN (-7875 4050) $PN 2
J 0
(-7913 4062);
DISPLAY 0.787234 (-7913 4062);
PAINT MONO (-7913 4062);
FORCEPROP 1 LAST WATTAGE 1/16W
J 2
(-7975 3950);
DISPLAY 0.638298 (-7975 3950);
FORCEPROP 1 LAST PACK_TYPE 0402LF
J 0
(-8125 4000);
DISPLAY 0.638298 (-8125 4000);
FORCEPROP 1 LAST TOLERANCE 5%
J 0
(-7925 4000);
DISPLAY 0.638298 (-7925 4000);
FORCEPROP 1 LAST VALUE 0
J 2
(-7825 4075);
DISPLAY 0.638298 (-7825 4075);
FORCEPROP 1 LAST MATERIAL EMPTY
J 0
(-7950 3950);
DISPLAY 0.638298 (-7950 3950);
FORCEPROP 2 LAST SEC_TYPE 0402LF
J 0
(-8025 4250);
DISPLAY 0.680851 (-8025 4250);
DISPLAY INVISIBLE (-8025 4250);
FORCEPROP 2 LAST CDS_LIB pure_quanta
J 0
(-7975 4050);
DISPLAY INVISIBLE (-7975 4050);
FORCEPROP 1 LAST PATH I32
J 0
(-8025 4200);
DISPLAY 0.978723 (-8025 4200);
PAINT WHITE (-8025 4200);
DISPLAY INVISIBLE (-8025 4200);
FORCEPROP 1 LAST PART_NUMBER CS00002JB13
J 0
(-8025 4150);
DISPLAY 0.978723 (-8025 4150);
DISPLAY INVISIBLE (-8025 4150);
FORCEADD Q_RES..1
(-7975 3850);
FORCEPROP 1 LAST LOCATION R6703
J 0
(-8250 3850);
DISPLAY 0.787234 (-8250 3850);
FORCEPROP 2 LAST SEC 1
J 0
(-8025 4050);
DISPLAY 0.680851 (-8025 4050);
PAINT MONO (-8025 4050);
DISPLAY INVISIBLE (-8025 4050);
FORCEPROP 1 LASTPIN (-8075 3850) $PN 1
J 0
(-8063 3862);
DISPLAY 0.787234 (-8063 3862);
PAINT MONO (-8063 3862);
FORCEPROP 1 LASTPIN (-7875 3850) $PN 2
J 0
(-7913 3862);
DISPLAY 0.787234 (-7913 3862);
PAINT MONO (-7913 3862);
FORCEPROP 1 LAST PACK_TYPE 0402LF
J 0
(-8125 3800);
DISPLAY 0.638298 (-8125 3800);
FORCEPROP 1 LAST WATTAGE 1/16W
J 2
(-7975 3750);
DISPLAY 0.638298 (-7975 3750);
FORCEPROP 1 LAST MATERIAL EMPTY
J 0
(-7950 3750);
DISPLAY 0.638298 (-7950 3750);
FORCEPROP 1 LAST TOLERANCE 5%
J 0
(-7925 3800);
DISPLAY 0.638298 (-7925 3800);
FORCEPROP 1 LAST VALUE 0
J 2
(-7825 3875);
DISPLAY 0.638298 (-7825 3875);
FORCEPROP 2 LAST CDS_LIB pure_quanta
J 0
(-7975 3850);
DISPLAY INVISIBLE (-7975 3850);
FORCEPROP 2 LAST SEC_TYPE 0402LF
J 0
(-8025 4050);
DISPLAY 0.680851 (-8025 4050);
DISPLAY INVISIBLE (-8025 4050);
FORCEPROP 1 LAST PATH I33
J 0
(-8025 4000);
DISPLAY 0.978723 (-8025 4000);
PAINT WHITE (-8025 4000);
DISPLAY INVISIBLE (-8025 4000);
FORCEPROP 1 LAST PART_NUMBER CS00002JB13
J 0
(-8025 3950);
DISPLAY 0.978723 (-8025 3950);
DISPLAY INVISIBLE (-8025 3950);
FORCEADD Q_CAP..1
(-3700 5750);
FORCEPROP 1 LAST LOCATION C229
J 0
(-3650 5850);
DISPLAY 0.978723 (-3650 5850);
PAINT WHITE (-3650 5850);
FORCEPROP 0 LAST $SEC 1
J 0
(-3650 5900);
DISPLAY 0.680851 (-3650 5900);
PAINT MONO (-3650 5900);
DISPLAY INVISIBLE (-3650 5900);
FORCEPROP 0 LAST CDS_SEC 1
J 0
(-3650 5900);
DISPLAY 0.680851 (-3650 5900);
DISPLAY INVISIBLE (-3650 5900);
FORCEPROP 1 LASTPIN (-3700 5850) $PN 1
J 0
(-3690 5830);
DISPLAY 0.787234 (-3690 5830);
PAINT MONO (-3690 5830);
FORCEPROP 1 LASTPIN (-3700 5650) $PN 2
J 0
(-3690 5630);
DISPLAY 0.787234 (-3690 5630);
PAINT MONO (-3690 5630);
FORCEPROP 1 LAST MATERIAL X6S
J 0
(-3650 5650);
DISPLAY 0.510638 (-3650 5650);
FORCEPROP 1 LAST PACK_TYPE C0805
J 0
(-3650 5600);
DISPLAY 0.510638 (-3650 5600);
FORCEPROP 1 LAST VOLTAGE 4V
J 0
(-3650 5750);
DISPLAY 0.510638 (-3650 5750);
FORCEPROP 1 LAST VALUE 100UF
J 0
(-3650 5800);
DISPLAY 0.510638 (-3650 5800);
FORCEPROP 1 LAST TOLERANCE 20%
J 0
(-3650 5700);
DISPLAY 0.510638 (-3650 5700);
FORCEPROP 2 LAST CDS_LIB pure_quanta
J 0
(-3700 5750);
DISPLAY INVISIBLE (-3700 5750);
FORCEPROP 1 LAST PATH I34
J 0
(-3650 5900);
DISPLAY 0.978723 (-3650 5900);
PAINT WHITE (-3650 5900);
DISPLAY INVISIBLE (-3650 5900);
FORCEPROP 1 LAST PART_NUMBER CH710KMEA01
J 0
(-3650 5600);
DISPLAY 0.404255 (-3650 5600);
DISPLAY INVISIBLE (-3650 5600);
FORCEADD Q_CAP..1
(-3425 5750);
FORCEPROP 1 LAST LOCATION C244
J 0
(-3375 5850);
DISPLAY 0.978723 (-3375 5850);
PAINT WHITE (-3375 5850);
FORCEPROP 0 LAST $SEC 1
J 0
(-3375 5900);
DISPLAY 0.680851 (-3375 5900);
PAINT MONO (-3375 5900);
DISPLAY INVISIBLE (-3375 5900);
FORCEPROP 0 LAST CDS_SEC 1
J 0
(-3375 5900);
DISPLAY 0.680851 (-3375 5900);
DISPLAY INVISIBLE (-3375 5900);
FORCEPROP 1 LASTPIN (-3425 5850) $PN 1
J 0
(-3415 5830);
DISPLAY 0.787234 (-3415 5830);
PAINT MONO (-3415 5830);
FORCEPROP 1 LASTPIN (-3425 5650) $PN 2
J 0
(-3415 5630);
DISPLAY 0.787234 (-3415 5630);
PAINT MONO (-3415 5630);
FORCEPROP 1 LAST MATERIAL X6S
J 0
(-3375 5650);
DISPLAY 0.510638 (-3375 5650);
FORCEPROP 1 LAST PACK_TYPE C0402
J 0
(-3375 5600);
DISPLAY 0.510638 (-3375 5600);
FORCEPROP 1 LAST VALUE 22UF
J 0
(-3375 5800);
DISPLAY 0.510638 (-3375 5800);
FORCEPROP 1 LAST VOLTAGE 4V
J 0
(-3375 5750);
DISPLAY 0.510638 (-3375 5750);
FORCEPROP 1 LAST TOLERANCE 20%
J 0
(-3375 5700);
DISPLAY 0.510638 (-3375 5700);
FORCEPROP 2 LAST CDS_LIB pure_quanta
J 0
(-3425 5750);
DISPLAY INVISIBLE (-3425 5750);
FORCEPROP 1 LAST PATH I35
J 0
(-3375 5900);
DISPLAY 0.978723 (-3375 5900);
PAINT WHITE (-3375 5900);
DISPLAY INVISIBLE (-3375 5900);
FORCEPROP 1 LAST PART_NUMBER CH622KMEB02
J 0
(-3375 5600);
DISPLAY 0.978723 (-3375 5600);
DISPLAY INVISIBLE (-3375 5600);
FORCEADD Q_CAP..1
(-3100 5725);
FORCEPROP 1 LAST LOCATION C261
J 0
(-3050 5825);
DISPLAY 0.978723 (-3050 5825);
PAINT WHITE (-3050 5825);
FORCEPROP 0 LAST $SEC 1
J 0
(-3050 5875);
DISPLAY 0.680851 (-3050 5875);
PAINT MONO (-3050 5875);
DISPLAY INVISIBLE (-3050 5875);
FORCEPROP 0 LAST CDS_SEC 1
J 0
(-3050 5875);
DISPLAY 0.680851 (-3050 5875);
DISPLAY INVISIBLE (-3050 5875);
FORCEPROP 1 LASTPIN (-3100 5825) $PN 1
J 0
(-3090 5805);
DISPLAY 0.787234 (-3090 5805);
PAINT MONO (-3090 5805);
FORCEPROP 1 LASTPIN (-3100 5625) $PN 2
J 0
(-3090 5605);
DISPLAY 0.787234 (-3090 5605);
PAINT MONO (-3090 5605);
FORCEPROP 1 LAST VOLTAGE 6.3V
J 0
(-3050 5725);
DISPLAY 0.510638 (-3050 5725);
FORCEPROP 1 LAST MATERIAL X6S
J 0
(-3050 5625);
DISPLAY 0.510638 (-3050 5625);
FORCEPROP 1 LAST PACK_TYPE C0402
J 0
(-3050 5575);
DISPLAY 0.510638 (-3050 5575);
FORCEPROP 1 LAST VALUE 10UF
J 0
(-3050 5775);
DISPLAY 0.510638 (-3050 5775);
FORCEPROP 1 LAST TOLERANCE 20%
J 0
(-3050 5675);
DISPLAY 0.510638 (-3050 5675);
FORCEPROP 2 LAST CDS_LIB pure_quanta
J 0
(-3100 5725);
DISPLAY INVISIBLE (-3100 5725);
FORCEPROP 1 LAST PATH I36
J 0
(-3050 5875);
DISPLAY 0.978723 (-3050 5875);
PAINT WHITE (-3050 5875);
DISPLAY INVISIBLE (-3050 5875);
FORCEPROP 1 LAST PART_NUMBER CH6101MEB01
J 0
(-3050 5575);
DISPLAY 0.978723 (-3050 5575);
DISPLAY INVISIBLE (-3050 5575);
FORCEADD VCC_CORE..1
(-4575 6250);
FORCEPROP 3 LASTPIN (-4575 6200) SIG_NAME P0V9_CPU1_RT_2D\g
J 0
(-4565 6210);
DISPLAY 0.659574 (-4565 6210);
PAINT MONO (-4565 6210);
DISPLAY INVISIBLE (-4565 6210);
FORCEPROP 1 LAST HDL_POWER P0V9_CPU1_RT_2D
J 1
(-4575 6300);
DISPLAY 0.617021 (-4575 6300);
PAINT GREEN (-4575 6300);
FORCEPROP 2 LAST CDS_LIB pure_quanta_power
J 0
(-4575 6250);
DISPLAY INVISIBLE (-4575 6250);
FORCEPROP 1 LAST PATH I37
J 0
(-4525 6275);
DISPLAY 0.872340 (-4525 6275);
PAINT AQUA (-4525 6275);
DISPLAY INVISIBLE (-4525 6275);
FORCEADD Q_CAP..1
(-2800 5725);
FORCEPROP 1 LAST LOCATION C256
J 0
(-2750 5825);
DISPLAY 0.978723 (-2750 5825);
PAINT WHITE (-2750 5825);
FORCEPROP 0 LAST $SEC 1
J 0
(-2750 5875);
DISPLAY 0.680851 (-2750 5875);
PAINT MONO (-2750 5875);
DISPLAY INVISIBLE (-2750 5875);
FORCEPROP 0 LAST CDS_SEC 1
J 0
(-2750 5875);
DISPLAY 0.680851 (-2750 5875);
DISPLAY INVISIBLE (-2750 5875);
FORCEPROP 1 LASTPIN (-2800 5825) $PN 1
J 0
(-2790 5805);
DISPLAY 0.787234 (-2790 5805);
PAINT MONO (-2790 5805);
FORCEPROP 1 LASTPIN (-2800 5625) $PN 2
J 0
(-2790 5605);
DISPLAY 0.787234 (-2790 5605);
PAINT MONO (-2790 5605);
FORCEPROP 1 LAST VALUE 4.7UF
J 0
(-2750 5775);
DISPLAY 0.510638 (-2750 5775);
FORCEPROP 1 LAST VOLTAGE 6.3V
J 0
(-2750 5725);
DISPLAY 0.510638 (-2750 5725);
FORCEPROP 1 LAST TOLERANCE 20%
J 0
(-2750 5675);
DISPLAY 0.510638 (-2750 5675);
FORCEPROP 1 LAST MATERIAL X6S
J 0
(-2750 5625);
DISPLAY 0.510638 (-2750 5625);
FORCEPROP 1 LAST PACK_TYPE 0402
J 0
(-2750 5575);
DISPLAY 0.510638 (-2750 5575);
FORCEPROP 2 LAST CDS_LIB pure_quanta
J 0
(-2800 5725);
DISPLAY INVISIBLE (-2800 5725);
FORCEPROP 1 LAST PATH I39
J 0
(-2750 5875);
DISPLAY 0.978723 (-2750 5875);
PAINT WHITE (-2750 5875);
DISPLAY INVISIBLE (-2750 5875);
FORCEPROP 1 LAST PART_NUMBER CH5471MEB01
J 0
(-2750 5575);
DISPLAY 0.978723 (-2750 5575);
DISPLAY INVISIBLE (-2750 5575);
FORCEADD Q_CAP..1
(-7475 4475);
FORCEPROP 1 LAST LOCATION C114
J 0
(-7425 4575);
DISPLAY 0.638298 (-7425 4575);
PAINT WHITE (-7425 4575);
FORCEPROP 0 LAST $SEC 1
J 0
(-7425 4600);
DISPLAY 0.680851 (-7425 4600);
PAINT MONO (-7425 4600);
DISPLAY INVISIBLE (-7425 4600);
FORCEPROP 0 LAST CDS_SEC 1
J 0
(-7425 4600);
DISPLAY 0.680851 (-7425 4600);
DISPLAY INVISIBLE (-7425 4600);
FORCEPROP 1 LASTPIN (-7475 4575) $PN 1
J 0
(-7465 4555);
DISPLAY 0.787234 (-7465 4555);
PAINT MONO (-7465 4555);
FORCEPROP 1 LASTPIN (-7475 4375) $PN 2
J 0
(-7465 4355);
DISPLAY 0.787234 (-7465 4355);
PAINT MONO (-7465 4355);
FORCEPROP 1 LAST PACK_TYPE C0805
J 0
(-7425 4325);
DISPLAY 0.510638 (-7425 4325);
FORCEPROP 1 LAST VOLTAGE 4V
J 0
(-7425 4475);
DISPLAY 0.510638 (-7425 4475);
FORCEPROP 1 LAST VALUE 100UF
J 0
(-7425 4525);
DISPLAY 0.510638 (-7425 4525);
FORCEPROP 1 LAST TOLERANCE 20%
J 0
(-7425 4425);
DISPLAY 0.510638 (-7425 4425);
FORCEPROP 1 LAST MATERIAL X6S
J 0
(-7425 4375);
DISPLAY 0.510638 (-7425 4375);
FORCEPROP 2 LAST CDS_LIB pure_quanta
J 0
(-7475 4475);
DISPLAY INVISIBLE (-7475 4475);
FORCEPROP 1 LAST PATH I4
J 0
(-7425 4625);
DISPLAY 0.978723 (-7425 4625);
PAINT WHITE (-7425 4625);
DISPLAY INVISIBLE (-7425 4625);
FORCEPROP 1 LAST PART_NUMBER CH710KMEA01
J 0
(-7425 4325);
DISPLAY 0.404255 (-7425 4325);
DISPLAY INVISIBLE (-7425 4325);
FORCEADD Q_CAP..1
(-2500 5725);
FORCEPROP 1 LAST LOCATION C185
J 0
(-2450 5825);
DISPLAY 0.978723 (-2450 5825);
PAINT WHITE (-2450 5825);
FORCEPROP 0 LAST $SEC 1
J 0
(-2450 5875);
DISPLAY 0.680851 (-2450 5875);
PAINT MONO (-2450 5875);
DISPLAY INVISIBLE (-2450 5875);
FORCEPROP 0 LAST CDS_SEC 1
J 0
(-2450 5875);
DISPLAY 0.680851 (-2450 5875);
DISPLAY INVISIBLE (-2450 5875);
FORCEPROP 1 LASTPIN (-2500 5825) $PN 1
J 0
(-2490 5805);
DISPLAY 0.787234 (-2490 5805);
PAINT MONO (-2490 5805);
FORCEPROP 1 LASTPIN (-2500 5625) $PN 2
J 0
(-2490 5605);
DISPLAY 0.787234 (-2490 5605);
PAINT MONO (-2490 5605);
FORCEPROP 1 LAST MATERIAL X6S
J 0
(-2450 5625);
DISPLAY 0.510638 (-2450 5625);
FORCEPROP 1 LAST PACK_TYPE 0201
J 0
(-2450 5575);
DISPLAY 0.510638 (-2450 5575);
FORCEPROP 1 LAST TOLERANCE 20%
J 0
(-2450 5675);
DISPLAY 0.510638 (-2450 5675);
FORCEPROP 1 LAST VALUE 1UF
J 0
(-2450 5775);
DISPLAY 0.510638 (-2450 5775);
FORCEPROP 1 LAST VOLTAGE 4V
J 0
(-2450 5725);
DISPLAY 0.510638 (-2450 5725);
FORCEPROP 2 LAST CDS_LIB pure_quanta
J 0
(-2500 5725);
DISPLAY INVISIBLE (-2500 5725);
FORCEPROP 1 LAST PATH I40
J 0
(-2450 5875);
DISPLAY 0.978723 (-2450 5875);
PAINT WHITE (-2450 5875);
DISPLAY INVISIBLE (-2450 5875);
FORCEPROP 1 LAST PART_NUMBER CH-10KMEE00
J 0
(-2450 5575);
DISPLAY 0.510638 (-2450 5575);
DISPLAY INVISIBLE (-2450 5575);
FORCEADD UNIVERSAL_GND..1
(-1150 2800);
FORCEPROP 3 LASTPIN (-1150 2850) SIG_NAME GND\g
J 0
(-1140 2860);
DISPLAY 0.659574 (-1140 2860);
PAINT MONO (-1140 2860);
DISPLAY INVISIBLE (-1140 2860);
FORCEPROP 2 LAST CDS_LIB pure_quanta_power
J 0
(-1150 2800);
DISPLAY INVISIBLE (-1150 2800);
FORCEPROP 1 LAST HDL_POWER GND
J 1
(-1125 2725);
DISPLAY 0.872340 (-1125 2725);
PAINT GREEN (-1125 2725);
DISPLAY INVISIBLE (-1125 2725);
FORCEPROP 1 LAST PATH I41
J 0
(-1075 2800);
DISPLAY 0.872340 (-1075 2800);
PAINT AQUA (-1075 2800);
DISPLAY INVISIBLE (-1075 2800);
FORCEADD Q_CAP..1
(-3750 3225);
FORCEPROP 1 LAST LOCATION C222
J 0
(-3700 3325);
DISPLAY 0.978723 (-3700 3325);
PAINT WHITE (-3700 3325);
FORCEPROP 0 LAST $SEC 1
J 0
(-3700 3375);
DISPLAY 0.680851 (-3700 3375);
PAINT MONO (-3700 3375);
DISPLAY INVISIBLE (-3700 3375);
FORCEPROP 0 LAST CDS_SEC 1
J 0
(-3700 3375);
DISPLAY 0.680851 (-3700 3375);
DISPLAY INVISIBLE (-3700 3375);
FORCEPROP 1 LASTPIN (-3750 3325) $PN 1
J 0
(-3740 3305);
DISPLAY 0.787234 (-3740 3305);
PAINT MONO (-3740 3305);
FORCEPROP 1 LASTPIN (-3750 3125) $PN 2
J 0
(-3740 3105);
DISPLAY 0.787234 (-3740 3105);
PAINT MONO (-3740 3105);
FORCEPROP 1 LAST TOLERANCE 20%
J 0
(-3700 3175);
DISPLAY 0.510638 (-3700 3175);
FORCEPROP 1 LAST VOLTAGE 4V
J 0
(-3700 3225);
DISPLAY 0.510638 (-3700 3225);
FORCEPROP 1 LAST PACK_TYPE 0201
J 0
(-3700 3075);
DISPLAY 0.510638 (-3700 3075);
FORCEPROP 1 LAST MATERIAL X6S
J 0
(-3700 3125);
DISPLAY 0.510638 (-3700 3125);
FORCEPROP 1 LAST VALUE 1UF
J 0
(-3700 3275);
DISPLAY 0.510638 (-3700 3275);
FORCEPROP 2 LAST CDS_LIB pure_quanta
J 0
(-3750 3225);
DISPLAY INVISIBLE (-3750 3225);
FORCEPROP 1 LAST PATH I42
J 0
(-3700 3375);
DISPLAY 0.978723 (-3700 3375);
PAINT WHITE (-3700 3375);
DISPLAY INVISIBLE (-3700 3375);
FORCEPROP 1 LAST PART_NUMBER CH-10KMEE00
J 0
(-3700 3075);
DISPLAY 0.510638 (-3700 3075);
DISPLAY INVISIBLE (-3700 3075);
FORCEADD Q_CAP..1
(-3750 4475);
FORCEPROP 1 LAST LOCATION C220
J 0
(-3700 4575);
DISPLAY 0.978723 (-3700 4575);
PAINT WHITE (-3700 4575);
FORCEPROP 0 LAST $SEC 1
J 0
(-3700 4625);
DISPLAY 0.680851 (-3700 4625);
PAINT MONO (-3700 4625);
DISPLAY INVISIBLE (-3700 4625);
FORCEPROP 0 LAST CDS_SEC 1
J 0
(-3700 4625);
DISPLAY 0.680851 (-3700 4625);
DISPLAY INVISIBLE (-3700 4625);
FORCEPROP 1 LASTPIN (-3750 4575) $PN 1
J 0
(-3740 4555);
DISPLAY 0.787234 (-3740 4555);
PAINT MONO (-3740 4555);
FORCEPROP 1 LASTPIN (-3750 4375) $PN 2
J 0
(-3740 4355);
DISPLAY 0.787234 (-3740 4355);
PAINT MONO (-3740 4355);
FORCEPROP 1 LAST MATERIAL X6S
J 0
(-3700 4375);
DISPLAY 0.510638 (-3700 4375);
FORCEPROP 1 LAST PACK_TYPE C0805
J 0
(-3700 4325);
DISPLAY 0.510638 (-3700 4325);
FORCEPROP 1 LAST TOLERANCE 20%
J 0
(-3700 4425);
DISPLAY 0.510638 (-3700 4425);
FORCEPROP 1 LAST VOLTAGE 4V
J 0
(-3700 4475);
DISPLAY 0.510638 (-3700 4475);
FORCEPROP 1 LAST VALUE 100UF
J 0
(-3700 4525);
DISPLAY 0.510638 (-3700 4525);
FORCEPROP 2 LAST CDS_LIB pure_quanta
J 0
(-3750 4475);
DISPLAY INVISIBLE (-3750 4475);
FORCEPROP 1 LAST PATH I44
J 0
(-3700 4625);
DISPLAY 0.978723 (-3700 4625);
PAINT WHITE (-3700 4625);
DISPLAY INVISIBLE (-3700 4625);
FORCEPROP 1 LAST PART_NUMBER CH710KMEA01
J 0
(-3700 4325);
DISPLAY 0.404255 (-3700 4325);
DISPLAY INVISIBLE (-3700 4325);
FORCEADD Q_CAP..1
(-3525 3225);
FORCEPROP 1 LAST LOCATION C135
J 0
(-3475 3325);
DISPLAY 0.978723 (-3475 3325);
PAINT WHITE (-3475 3325);
FORCEPROP 0 LAST $SEC 1
J 0
(-3475 3375);
DISPLAY 0.680851 (-3475 3375);
PAINT MONO (-3475 3375);
DISPLAY INVISIBLE (-3475 3375);
FORCEPROP 0 LAST CDS_SEC 1
J 0
(-3475 3375);
DISPLAY 0.680851 (-3475 3375);
DISPLAY INVISIBLE (-3475 3375);
FORCEPROP 1 LASTPIN (-3525 3325) $PN 1
J 0
(-3515 3305);
DISPLAY 0.787234 (-3515 3305);
PAINT MONO (-3515 3305);
FORCEPROP 1 LASTPIN (-3525 3125) $PN 2
J 0
(-3515 3105);
DISPLAY 0.787234 (-3515 3105);
PAINT MONO (-3515 3105);
FORCEPROP 1 LAST VOLTAGE 4V
J 0
(-3475 3225);
DISPLAY 0.510638 (-3475 3225);
FORCEPROP 1 LAST TOLERANCE 20%
J 0
(-3475 3175);
DISPLAY 0.510638 (-3475 3175);
FORCEPROP 1 LAST MATERIAL X6S
J 0
(-3475 3125);
DISPLAY 0.510638 (-3475 3125);
FORCEPROP 1 LAST VALUE 1UF
J 0
(-3475 3275);
DISPLAY 0.510638 (-3475 3275);
FORCEPROP 1 LAST PACK_TYPE 0201
J 0
(-3475 3075);
DISPLAY 0.510638 (-3475 3075);
FORCEPROP 2 LAST CDS_LIB pure_quanta
J 0
(-3525 3225);
DISPLAY INVISIBLE (-3525 3225);
FORCEPROP 1 LAST PATH I46
J 0
(-3475 3375);
DISPLAY 0.978723 (-3475 3375);
PAINT WHITE (-3475 3375);
DISPLAY INVISIBLE (-3475 3375);
FORCEPROP 1 LAST PART_NUMBER CH-10KMEE00
J 0
(-3475 3075);
DISPLAY 0.510638 (-3475 3075);
DISPLAY INVISIBLE (-3475 3075);
FORCEADD Q_CAP..1
(-3275 3225);
FORCEPROP 1 LAST LOCATION C243
J 0
(-3225 3325);
DISPLAY 0.978723 (-3225 3325);
PAINT WHITE (-3225 3325);
FORCEPROP 0 LAST $SEC 1
J 0
(-3225 3375);
DISPLAY 0.680851 (-3225 3375);
PAINT MONO (-3225 3375);
DISPLAY INVISIBLE (-3225 3375);
FORCEPROP 0 LAST CDS_SEC 1
J 0
(-3225 3375);
DISPLAY 0.680851 (-3225 3375);
DISPLAY INVISIBLE (-3225 3375);
FORCEPROP 1 LASTPIN (-3275 3325) $PN 1
J 0
(-3265 3305);
DISPLAY 0.787234 (-3265 3305);
PAINT MONO (-3265 3305);
FORCEPROP 1 LASTPIN (-3275 3125) $PN 2
J 0
(-3265 3105);
DISPLAY 0.787234 (-3265 3105);
PAINT MONO (-3265 3105);
FORCEPROP 1 LAST PACK_TYPE 0201
J 0
(-3225 3075);
DISPLAY 0.510638 (-3225 3075);
FORCEPROP 1 LAST MATERIAL X6S
J 0
(-3225 3125);
DISPLAY 0.510638 (-3225 3125);
FORCEPROP 1 LAST VALUE 1UF
J 0
(-3225 3275);
DISPLAY 0.510638 (-3225 3275);
FORCEPROP 1 LAST TOLERANCE 20%
J 0
(-3225 3175);
DISPLAY 0.510638 (-3225 3175);
FORCEPROP 1 LAST VOLTAGE 4V
J 0
(-3225 3225);
DISPLAY 0.510638 (-3225 3225);
FORCEPROP 2 LAST CDS_LIB pure_quanta
J 0
(-3275 3225);
DISPLAY INVISIBLE (-3275 3225);
FORCEPROP 1 LAST PATH I47
J 0
(-3225 3375);
DISPLAY 0.978723 (-3225 3375);
PAINT WHITE (-3225 3375);
DISPLAY INVISIBLE (-3225 3375);
FORCEPROP 1 LAST PART_NUMBER CH-10KMEE00
J 0
(-3225 3075);
DISPLAY 0.510638 (-3225 3075);
DISPLAY INVISIBLE (-3225 3075);
FORCEADD Q_CAP..1
(-3050 3225);
FORCEPROP 1 LAST LOCATION C138
J 0
(-3000 3325);
DISPLAY 0.978723 (-3000 3325);
PAINT WHITE (-3000 3325);
FORCEPROP 0 LAST $SEC 1
J 0
(-3000 3375);
DISPLAY 0.680851 (-3000 3375);
PAINT MONO (-3000 3375);
DISPLAY INVISIBLE (-3000 3375);
FORCEPROP 0 LAST CDS_SEC 1
J 0
(-3000 3375);
DISPLAY 0.680851 (-3000 3375);
DISPLAY INVISIBLE (-3000 3375);
FORCEPROP 1 LASTPIN (-3050 3325) $PN 1
J 0
(-3040 3305);
DISPLAY 0.787234 (-3040 3305);
PAINT MONO (-3040 3305);
FORCEPROP 1 LASTPIN (-3050 3125) $PN 2
J 0
(-3040 3105);
DISPLAY 0.787234 (-3040 3105);
PAINT MONO (-3040 3105);
FORCEPROP 1 LAST PACK_TYPE 0201
J 0
(-3000 3075);
DISPLAY 0.510638 (-3000 3075);
FORCEPROP 1 LAST MATERIAL X6S
J 0
(-3000 3125);
DISPLAY 0.510638 (-3000 3125);
FORCEPROP 1 LAST VALUE 1UF
J 0
(-3000 3275);
DISPLAY 0.510638 (-3000 3275);
FORCEPROP 1 LAST TOLERANCE 20%
J 0
(-3000 3175);
DISPLAY 0.510638 (-3000 3175);
FORCEPROP 1 LAST VOLTAGE 4V
J 0
(-3000 3225);
DISPLAY 0.510638 (-3000 3225);
FORCEPROP 2 LAST CDS_LIB pure_quanta
J 0
(-3050 3225);
DISPLAY INVISIBLE (-3050 3225);
FORCEPROP 1 LAST PATH I48
J 0
(-3000 3375);
DISPLAY 0.978723 (-3000 3375);
PAINT WHITE (-3000 3375);
DISPLAY INVISIBLE (-3000 3375);
FORCEPROP 1 LAST PART_NUMBER CH-10KMEE00
J 0
(-3000 3075);
DISPLAY 0.510638 (-3000 3075);
DISPLAY INVISIBLE (-3000 3075);
FORCEADD Q_CAP..1
(-2800 3225);
FORCEPROP 1 LAST LOCATION C257
J 0
(-2750 3325);
DISPLAY 0.978723 (-2750 3325);
PAINT WHITE (-2750 3325);
FORCEPROP 0 LAST $SEC 1
J 0
(-2750 3375);
DISPLAY 0.680851 (-2750 3375);
PAINT MONO (-2750 3375);
DISPLAY INVISIBLE (-2750 3375);
FORCEPROP 0 LAST CDS_SEC 1
J 0
(-2750 3375);
DISPLAY 0.680851 (-2750 3375);
DISPLAY INVISIBLE (-2750 3375);
FORCEPROP 1 LASTPIN (-2800 3325) $PN 1
J 0
(-2790 3305);
DISPLAY 0.787234 (-2790 3305);
PAINT MONO (-2790 3305);
FORCEPROP 1 LASTPIN (-2800 3125) $PN 2
J 0
(-2790 3105);
DISPLAY 0.787234 (-2790 3105);
PAINT MONO (-2790 3105);
FORCEPROP 1 LAST VALUE 1UF
J 0
(-2750 3275);
DISPLAY 0.510638 (-2750 3275);
FORCEPROP 1 LAST VOLTAGE 4V
J 0
(-2750 3225);
DISPLAY 0.510638 (-2750 3225);
FORCEPROP 1 LAST PACK_TYPE 0201
J 0
(-2750 3075);
DISPLAY 0.510638 (-2750 3075);
FORCEPROP 1 LAST MATERIAL X6S
J 0
(-2750 3125);
DISPLAY 0.510638 (-2750 3125);
FORCEPROP 1 LAST TOLERANCE 20%
J 0
(-2750 3175);
DISPLAY 0.510638 (-2750 3175);
FORCEPROP 2 LAST CDS_LIB pure_quanta
J 0
(-2800 3225);
DISPLAY INVISIBLE (-2800 3225);
FORCEPROP 1 LAST PATH I49
J 0
(-2750 3375);
DISPLAY 0.978723 (-2750 3375);
PAINT WHITE (-2750 3375);
DISPLAY INVISIBLE (-2750 3375);
FORCEPROP 1 LAST PART_NUMBER CH-10KMEE00
J 0
(-2750 3075);
DISPLAY 0.510638 (-2750 3075);
DISPLAY INVISIBLE (-2750 3075);
FORCEADD Q_CAP..1
(-7250 4475);
FORCEPROP 1 LAST LOCATION C117
J 0
(-7200 4575);
DISPLAY 0.638298 (-7200 4575);
PAINT WHITE (-7200 4575);
FORCEPROP 0 LAST $SEC 1
J 0
(-7200 4600);
DISPLAY 0.680851 (-7200 4600);
PAINT MONO (-7200 4600);
DISPLAY INVISIBLE (-7200 4600);
FORCEPROP 0 LAST CDS_SEC 1
J 0
(-7200 4600);
DISPLAY 0.680851 (-7200 4600);
DISPLAY INVISIBLE (-7200 4600);
FORCEPROP 1 LASTPIN (-7250 4575) $PN 1
J 0
(-7240 4555);
DISPLAY 0.787234 (-7240 4555);
PAINT MONO (-7240 4555);
FORCEPROP 1 LASTPIN (-7250 4375) $PN 2
J 0
(-7240 4355);
DISPLAY 0.787234 (-7240 4355);
PAINT MONO (-7240 4355);
FORCEPROP 1 LAST VALUE 22UF
J 0
(-7200 4525);
DISPLAY 0.510638 (-7200 4525);
FORCEPROP 1 LAST TOLERANCE 20%
J 0
(-7200 4425);
DISPLAY 0.510638 (-7200 4425);
FORCEPROP 1 LAST MATERIAL X6S
J 0
(-7200 4375);
DISPLAY 0.510638 (-7200 4375);
FORCEPROP 1 LAST VOLTAGE 4V
J 0
(-7200 4475);
DISPLAY 0.510638 (-7200 4475);
FORCEPROP 1 LAST PACK_TYPE C0402
J 0
(-7200 4325);
DISPLAY 0.510638 (-7200 4325);
FORCEPROP 2 LAST CDS_LIB pure_quanta
J 0
(-7250 4475);
DISPLAY INVISIBLE (-7250 4475);
FORCEPROP 1 LAST PATH I5
J 0
(-7200 4625);
DISPLAY 0.978723 (-7200 4625);
PAINT WHITE (-7200 4625);
DISPLAY INVISIBLE (-7200 4625);
FORCEPROP 1 LAST PART_NUMBER CH622KMEB02
J 0
(-7200 4325);
DISPLAY 0.978723 (-7200 4325);
DISPLAY INVISIBLE (-7200 4325);
FORCEADD Q_CAP..1
(-3075 3850);
FORCEPROP 1 LAST LOCATION C221
J 0
(-3025 3950);
DISPLAY 0.978723 (-3025 3950);
PAINT WHITE (-3025 3950);
FORCEPROP 0 LAST $SEC 1
J 0
(-3025 4000);
DISPLAY 0.680851 (-3025 4000);
PAINT MONO (-3025 4000);
DISPLAY INVISIBLE (-3025 4000);
FORCEPROP 0 LAST CDS_SEC 1
J 0
(-3025 4000);
DISPLAY 0.680851 (-3025 4000);
DISPLAY INVISIBLE (-3025 4000);
FORCEPROP 1 LASTPIN (-3075 3950) $PN 1
J 0
(-3065 3930);
DISPLAY 0.787234 (-3065 3930);
PAINT MONO (-3065 3930);
FORCEPROP 1 LASTPIN (-3075 3750) $PN 2
J 0
(-3065 3730);
DISPLAY 0.787234 (-3065 3730);
PAINT MONO (-3065 3730);
FORCEPROP 1 LAST PACK_TYPE 0402
J 0
(-3025 3700);
DISPLAY 0.510638 (-3025 3700);
FORCEPROP 1 LAST VOLTAGE 6.3V
J 0
(-3025 3850);
DISPLAY 0.510638 (-3025 3850);
FORCEPROP 1 LAST TOLERANCE 20%
J 0
(-3025 3800);
DISPLAY 0.510638 (-3025 3800);
FORCEPROP 1 LAST MATERIAL X6S
J 0
(-3025 3750);
DISPLAY 0.510638 (-3025 3750);
FORCEPROP 1 LAST VALUE 4.7UF
J 0
(-3025 3900);
DISPLAY 0.510638 (-3025 3900);
FORCEPROP 2 LAST CDS_LIB pure_quanta
J 0
(-3075 3850);
DISPLAY INVISIBLE (-3075 3850);
FORCEPROP 1 LAST PATH I50
J 0
(-3025 4000);
DISPLAY 0.978723 (-3025 4000);
PAINT WHITE (-3025 4000);
DISPLAY INVISIBLE (-3025 4000);
FORCEPROP 1 LAST PART_NUMBER CH5471MEB01
J 0
(-3025 3700);
DISPLAY 0.978723 (-3025 3700);
DISPLAY INVISIBLE (-3025 3700);
FORCEADD Q_CAP..1
(-2825 3850);
FORCEPROP 1 LAST LOCATION C258
J 0
(-2775 3950);
DISPLAY 0.978723 (-2775 3950);
PAINT WHITE (-2775 3950);
FORCEPROP 0 LAST $SEC 1
J 0
(-2775 4000);
DISPLAY 0.680851 (-2775 4000);
PAINT MONO (-2775 4000);
DISPLAY INVISIBLE (-2775 4000);
FORCEPROP 0 LAST CDS_SEC 1
J 0
(-2775 4000);
DISPLAY 0.680851 (-2775 4000);
DISPLAY INVISIBLE (-2775 4000);
FORCEPROP 1 LASTPIN (-2825 3950) $PN 1
J 0
(-2815 3930);
DISPLAY 0.787234 (-2815 3930);
PAINT MONO (-2815 3930);
FORCEPROP 1 LASTPIN (-2825 3750) $PN 2
J 0
(-2815 3730);
DISPLAY 0.787234 (-2815 3730);
PAINT MONO (-2815 3730);
FORCEPROP 1 LAST PACK_TYPE 0402
J 0
(-2775 3700);
DISPLAY 0.510638 (-2775 3700);
FORCEPROP 1 LAST VOLTAGE 6.3V
J 0
(-2775 3850);
DISPLAY 0.510638 (-2775 3850);
FORCEPROP 1 LAST TOLERANCE 20%
J 0
(-2775 3800);
DISPLAY 0.510638 (-2775 3800);
FORCEPROP 1 LAST VALUE 4.7UF
J 0
(-2775 3900);
DISPLAY 0.510638 (-2775 3900);
FORCEPROP 1 LAST MATERIAL X6S
J 0
(-2775 3750);
DISPLAY 0.510638 (-2775 3750);
FORCEPROP 2 LAST CDS_LIB pure_quanta
J 0
(-2825 3850);
DISPLAY INVISIBLE (-2825 3850);
FORCEPROP 1 LAST PATH I51
J 0
(-2775 4000);
DISPLAY 0.978723 (-2775 4000);
PAINT WHITE (-2775 4000);
DISPLAY INVISIBLE (-2775 4000);
FORCEPROP 1 LAST PART_NUMBER CH5471MEB01
J 0
(-2775 3700);
DISPLAY 0.978723 (-2775 3700);
DISPLAY INVISIBLE (-2775 3700);
FORCEADD Q_CAP..1
(-3525 4475);
FORCEPROP 1 LAST LOCATION C225
J 0
(-3475 4575);
DISPLAY 0.978723 (-3475 4575);
PAINT WHITE (-3475 4575);
FORCEPROP 0 LAST $SEC 1
J 0
(-3475 4625);
DISPLAY 0.680851 (-3475 4625);
PAINT MONO (-3475 4625);
DISPLAY INVISIBLE (-3475 4625);
FORCEPROP 0 LAST CDS_SEC 1
J 0
(-3475 4625);
DISPLAY 0.680851 (-3475 4625);
DISPLAY INVISIBLE (-3475 4625);
FORCEPROP 1 LASTPIN (-3525 4575) $PN 1
J 0
(-3515 4555);
DISPLAY 0.787234 (-3515 4555);
PAINT MONO (-3515 4555);
FORCEPROP 1 LASTPIN (-3525 4375) $PN 2
J 0
(-3515 4355);
DISPLAY 0.787234 (-3515 4355);
PAINT MONO (-3515 4355);
FORCEPROP 1 LAST VALUE 100UF
J 0
(-3475 4525);
DISPLAY 0.510638 (-3475 4525);
FORCEPROP 1 LAST VOLTAGE 4V
J 0
(-3475 4475);
DISPLAY 0.510638 (-3475 4475);
FORCEPROP 1 LAST TOLERANCE 20%
J 0
(-3475 4425);
DISPLAY 0.510638 (-3475 4425);
FORCEPROP 1 LAST MATERIAL X6S
J 0
(-3475 4375);
DISPLAY 0.510638 (-3475 4375);
FORCEPROP 1 LAST PACK_TYPE C0805
J 0
(-3475 4325);
DISPLAY 0.510638 (-3475 4325);
FORCEPROP 2 LAST CDS_LIB pure_quanta
J 0
(-3525 4475);
DISPLAY INVISIBLE (-3525 4475);
FORCEPROP 1 LAST PATH I52
J 0
(-3475 4625);
DISPLAY 0.978723 (-3475 4625);
PAINT WHITE (-3475 4625);
DISPLAY INVISIBLE (-3475 4625);
FORCEPROP 1 LAST PART_NUMBER CH710KMEA01
J 0
(-3475 4325);
DISPLAY 0.404255 (-3475 4325);
DISPLAY INVISIBLE (-3475 4325);
FORCEADD Q_CAP..1
(-3300 4475);
FORCEPROP 1 LAST LOCATION C240
J 0
(-3250 4575);
DISPLAY 0.978723 (-3250 4575);
PAINT WHITE (-3250 4575);
FORCEPROP 0 LAST $SEC 1
J 0
(-3250 4625);
DISPLAY 0.680851 (-3250 4625);
PAINT MONO (-3250 4625);
DISPLAY INVISIBLE (-3250 4625);
FORCEPROP 0 LAST CDS_SEC 1
J 0
(-3250 4625);
DISPLAY 0.680851 (-3250 4625);
DISPLAY INVISIBLE (-3250 4625);
FORCEPROP 1 LASTPIN (-3300 4575) $PN 1
J 0
(-3290 4555);
DISPLAY 0.787234 (-3290 4555);
PAINT MONO (-3290 4555);
FORCEPROP 1 LASTPIN (-3300 4375) $PN 2
J 0
(-3290 4355);
DISPLAY 0.787234 (-3290 4355);
PAINT MONO (-3290 4355);
FORCEPROP 1 LAST VALUE 100UF
J 0
(-3250 4525);
DISPLAY 0.510638 (-3250 4525);
FORCEPROP 1 LAST VOLTAGE 4V
J 0
(-3250 4475);
DISPLAY 0.510638 (-3250 4475);
FORCEPROP 1 LAST TOLERANCE 20%
J 0
(-3250 4425);
DISPLAY 0.510638 (-3250 4425);
FORCEPROP 1 LAST MATERIAL X6S
J 0
(-3250 4375);
DISPLAY 0.510638 (-3250 4375);
FORCEPROP 1 LAST PACK_TYPE C0805
J 0
(-3250 4325);
DISPLAY 0.510638 (-3250 4325);
FORCEPROP 2 LAST CDS_LIB pure_quanta
J 0
(-3300 4475);
DISPLAY INVISIBLE (-3300 4475);
FORCEPROP 1 LAST PATH I53
J 0
(-3250 4625);
DISPLAY 0.978723 (-3250 4625);
PAINT WHITE (-3250 4625);
DISPLAY INVISIBLE (-3250 4625);
FORCEPROP 1 LAST PART_NUMBER CH710KMEA01
J 0
(-3250 4325);
DISPLAY 0.404255 (-3250 4325);
DISPLAY INVISIBLE (-3250 4325);
FORCEADD Q_CAP..1
(-2825 4475);
FORCEPROP 1 LAST LOCATION C284
J 0
(-2775 4575);
DISPLAY 0.978723 (-2775 4575);
PAINT WHITE (-2775 4575);
FORCEPROP 0 LAST $SEC 1
J 0
(-2775 4625);
DISPLAY 0.680851 (-2775 4625);
PAINT MONO (-2775 4625);
DISPLAY INVISIBLE (-2775 4625);
FORCEPROP 0 LAST CDS_SEC 1
J 0
(-2775 4625);
DISPLAY 0.680851 (-2775 4625);
DISPLAY INVISIBLE (-2775 4625);
FORCEPROP 1 LASTPIN (-2825 4575) $PN 1
J 0
(-2815 4555);
DISPLAY 0.787234 (-2815 4555);
PAINT MONO (-2815 4555);
FORCEPROP 1 LASTPIN (-2825 4375) $PN 2
J 0
(-2815 4355);
DISPLAY 0.787234 (-2815 4355);
PAINT MONO (-2815 4355);
FORCEPROP 1 LAST TOLERANCE 20%
J 0
(-2775 4425);
DISPLAY 0.510638 (-2775 4425);
FORCEPROP 1 LAST VOLTAGE 4V
J 0
(-2775 4475);
DISPLAY 0.510638 (-2775 4475);
FORCEPROP 1 LAST MATERIAL X6S
J 0
(-2775 4375);
DISPLAY 0.510638 (-2775 4375);
FORCEPROP 1 LAST VALUE 22UF
J 0
(-2775 4525);
DISPLAY 0.510638 (-2775 4525);
FORCEPROP 1 LAST PACK_TYPE C0402
J 0
(-2775 4325);
DISPLAY 0.510638 (-2775 4325);
FORCEPROP 2 LAST CDS_LIB pure_quanta
J 0
(-2825 4475);
DISPLAY INVISIBLE (-2825 4475);
FORCEPROP 1 LAST PATH I54
J 0
(-2775 4625);
DISPLAY 0.978723 (-2775 4625);
PAINT WHITE (-2775 4625);
DISPLAY INVISIBLE (-2775 4625);
FORCEPROP 1 LAST PART_NUMBER CH622KMEB02
J 0
(-2775 4325);
DISPLAY 0.978723 (-2775 4325);
DISPLAY INVISIBLE (-2775 4325);
FORCEADD Q_CAP..1
(-2575 3200);
FORCEPROP 1 LAST LOCATION C188
J 0
(-2525 3300);
DISPLAY 0.978723 (-2525 3300);
PAINT WHITE (-2525 3300);
FORCEPROP 0 LAST $SEC 1
J 0
(-2525 3350);
DISPLAY 0.680851 (-2525 3350);
PAINT MONO (-2525 3350);
DISPLAY INVISIBLE (-2525 3350);
FORCEPROP 0 LAST CDS_SEC 1
J 0
(-2525 3350);
DISPLAY 0.680851 (-2525 3350);
DISPLAY INVISIBLE (-2525 3350);
FORCEPROP 1 LASTPIN (-2575 3300) $PN 1
J 0
(-2565 3280);
DISPLAY 0.787234 (-2565 3280);
PAINT MONO (-2565 3280);
FORCEPROP 1 LASTPIN (-2575 3100) $PN 2
J 0
(-2565 3080);
DISPLAY 0.787234 (-2565 3080);
PAINT MONO (-2565 3080);
FORCEPROP 1 LAST VOLTAGE 4V
J 0
(-2525 3200);
DISPLAY 0.510638 (-2525 3200);
FORCEPROP 1 LAST TOLERANCE 20%
J 0
(-2525 3150);
DISPLAY 0.510638 (-2525 3150);
FORCEPROP 1 LAST VALUE 1UF
J 0
(-2525 3250);
DISPLAY 0.510638 (-2525 3250);
FORCEPROP 1 LAST MATERIAL X6S
J 0
(-2525 3100);
DISPLAY 0.510638 (-2525 3100);
FORCEPROP 1 LAST PACK_TYPE 0201
J 0
(-2525 3050);
DISPLAY 0.510638 (-2525 3050);
FORCEPROP 2 LAST CDS_LIB pure_quanta
J 0
(-2575 3200);
DISPLAY INVISIBLE (-2575 3200);
FORCEPROP 1 LAST PATH I55
J 0
(-2525 3350);
DISPLAY 0.978723 (-2525 3350);
PAINT WHITE (-2525 3350);
DISPLAY INVISIBLE (-2525 3350);
FORCEPROP 1 LAST PART_NUMBER CH-10KMEE00
J 0
(-2525 3050);
DISPLAY 0.510638 (-2525 3050);
DISPLAY INVISIBLE (-2525 3050);
FORCEADD Q_CAP..1
(-2350 3200);
FORCEPROP 1 LAST LOCATION C265
J 0
(-2300 3300);
DISPLAY 0.978723 (-2300 3300);
PAINT WHITE (-2300 3300);
FORCEPROP 0 LAST $SEC 1
J 0
(-2300 3350);
DISPLAY 0.680851 (-2300 3350);
PAINT MONO (-2300 3350);
DISPLAY INVISIBLE (-2300 3350);
FORCEPROP 0 LAST CDS_SEC 1
J 0
(-2300 3350);
DISPLAY 0.680851 (-2300 3350);
DISPLAY INVISIBLE (-2300 3350);
FORCEPROP 1 LASTPIN (-2350 3300) $PN 1
J 0
(-2340 3280);
DISPLAY 0.787234 (-2340 3280);
PAINT MONO (-2340 3280);
FORCEPROP 1 LASTPIN (-2350 3100) $PN 2
J 0
(-2340 3080);
DISPLAY 0.787234 (-2340 3080);
PAINT MONO (-2340 3080);
FORCEPROP 1 LAST PACK_TYPE 0201
J 0
(-2300 3050);
DISPLAY 0.510638 (-2300 3050);
FORCEPROP 1 LAST TOLERANCE 20%
J 0
(-2300 3150);
DISPLAY 0.510638 (-2300 3150);
FORCEPROP 1 LAST VOLTAGE 4V
J 0
(-2300 3200);
DISPLAY 0.510638 (-2300 3200);
FORCEPROP 1 LAST VALUE 1UF
J 0
(-2300 3250);
DISPLAY 0.510638 (-2300 3250);
FORCEPROP 1 LAST MATERIAL X6S
J 0
(-2300 3100);
DISPLAY 0.510638 (-2300 3100);
FORCEPROP 2 LAST CDS_LIB pure_quanta
J 0
(-2350 3200);
DISPLAY INVISIBLE (-2350 3200);
FORCEPROP 1 LAST PATH I56
J 0
(-2300 3350);
DISPLAY 0.978723 (-2300 3350);
PAINT WHITE (-2300 3350);
DISPLAY INVISIBLE (-2300 3350);
FORCEPROP 1 LAST PART_NUMBER CH-10KMEE00
J 0
(-2300 3050);
DISPLAY 0.510638 (-2300 3050);
DISPLAY INVISIBLE (-2300 3050);
FORCEADD Q_CAP..1
(-2600 3850);
FORCEPROP 1 LAST LOCATION C227
J 0
(-2550 3950);
DISPLAY 0.978723 (-2550 3950);
PAINT WHITE (-2550 3950);
FORCEPROP 0 LAST $SEC 1
J 0
(-2550 4000);
DISPLAY 0.680851 (-2550 4000);
PAINT MONO (-2550 4000);
DISPLAY INVISIBLE (-2550 4000);
FORCEPROP 0 LAST CDS_SEC 1
J 0
(-2550 4000);
DISPLAY 0.680851 (-2550 4000);
DISPLAY INVISIBLE (-2550 4000);
FORCEPROP 1 LASTPIN (-2600 3950) $PN 1
J 0
(-2590 3930);
DISPLAY 0.787234 (-2590 3930);
PAINT MONO (-2590 3930);
FORCEPROP 1 LASTPIN (-2600 3750) $PN 2
J 0
(-2590 3730);
DISPLAY 0.787234 (-2590 3730);
PAINT MONO (-2590 3730);
FORCEPROP 1 LAST PACK_TYPE 0402
J 0
(-2550 3700);
DISPLAY 0.510638 (-2550 3700);
FORCEPROP 1 LAST MATERIAL X6S
J 0
(-2550 3750);
DISPLAY 0.510638 (-2550 3750);
FORCEPROP 1 LAST VOLTAGE 6.3V
J 0
(-2550 3850);
DISPLAY 0.510638 (-2550 3850);
FORCEPROP 1 LAST TOLERANCE 20%
J 0
(-2550 3800);
DISPLAY 0.510638 (-2550 3800);
FORCEPROP 1 LAST VALUE 4.7UF
J 0
(-2550 3900);
DISPLAY 0.510638 (-2550 3900);
FORCEPROP 2 LAST CDS_LIB pure_quanta
J 0
(-2600 3850);
DISPLAY INVISIBLE (-2600 3850);
FORCEPROP 1 LAST PATH I57
J 0
(-2550 4000);
DISPLAY 0.978723 (-2550 4000);
PAINT WHITE (-2550 4000);
DISPLAY INVISIBLE (-2550 4000);
FORCEPROP 1 LAST PART_NUMBER CH5471MEB01
J 0
(-2550 3700);
DISPLAY 0.978723 (-2550 3700);
DISPLAY INVISIBLE (-2550 3700);
FORCEADD Q_CAP..1
(-2375 3850);
FORCEPROP 1 LAST LOCATION C186
J 0
(-2325 3950);
DISPLAY 0.978723 (-2325 3950);
PAINT WHITE (-2325 3950);
FORCEPROP 0 LAST $SEC 1
J 0
(-2325 4000);
DISPLAY 0.680851 (-2325 4000);
PAINT MONO (-2325 4000);
DISPLAY INVISIBLE (-2325 4000);
FORCEPROP 0 LAST CDS_SEC 1
J 0
(-2325 4000);
DISPLAY 0.680851 (-2325 4000);
DISPLAY INVISIBLE (-2325 4000);
FORCEPROP 1 LASTPIN (-2375 3950) $PN 1
J 0
(-2365 3930);
DISPLAY 0.787234 (-2365 3930);
PAINT MONO (-2365 3930);
FORCEPROP 1 LASTPIN (-2375 3750) $PN 2
J 0
(-2365 3730);
DISPLAY 0.787234 (-2365 3730);
PAINT MONO (-2365 3730);
FORCEPROP 1 LAST MATERIAL X6S
J 0
(-2325 3750);
DISPLAY 0.510638 (-2325 3750);
FORCEPROP 1 LAST VALUE 1UF
J 0
(-2325 3900);
DISPLAY 0.510638 (-2325 3900);
FORCEPROP 1 LAST VOLTAGE 4V
J 0
(-2325 3850);
DISPLAY 0.510638 (-2325 3850);
FORCEPROP 1 LAST PACK_TYPE 0201
J 0
(-2325 3700);
DISPLAY 0.510638 (-2325 3700);
FORCEPROP 1 LAST TOLERANCE 20%
J 0
(-2325 3800);
DISPLAY 0.510638 (-2325 3800);
FORCEPROP 2 LAST CDS_LIB pure_quanta
J 0
(-2375 3850);
DISPLAY INVISIBLE (-2375 3850);
FORCEPROP 1 LAST PATH I58
J 0
(-2325 4000);
DISPLAY 0.978723 (-2325 4000);
PAINT WHITE (-2325 4000);
DISPLAY INVISIBLE (-2325 4000);
FORCEPROP 1 LAST PART_NUMBER CH-10KMEE00
J 0
(-2325 3700);
DISPLAY 0.510638 (-2325 3700);
DISPLAY INVISIBLE (-2325 3700);
FORCEADD Q_CAP..1
(-2150 3850);
FORCEPROP 1 LAST LOCATION C280
J 0
(-2100 3950);
DISPLAY 0.978723 (-2100 3950);
PAINT WHITE (-2100 3950);
FORCEPROP 0 LAST $SEC 1
J 0
(-2100 4000);
DISPLAY 0.680851 (-2100 4000);
PAINT MONO (-2100 4000);
DISPLAY INVISIBLE (-2100 4000);
FORCEPROP 0 LAST CDS_SEC 1
J 0
(-2100 4000);
DISPLAY 0.680851 (-2100 4000);
DISPLAY INVISIBLE (-2100 4000);
FORCEPROP 1 LASTPIN (-2150 3950) $PN 1
J 0
(-2140 3930);
DISPLAY 0.787234 (-2140 3930);
PAINT MONO (-2140 3930);
FORCEPROP 1 LASTPIN (-2150 3750) $PN 2
J 0
(-2140 3730);
DISPLAY 0.787234 (-2140 3730);
PAINT MONO (-2140 3730);
FORCEPROP 1 LAST VOLTAGE 4V
J 0
(-2100 3850);
DISPLAY 0.510638 (-2100 3850);
FORCEPROP 1 LAST TOLERANCE 20%
J 0
(-2100 3800);
DISPLAY 0.510638 (-2100 3800);
FORCEPROP 1 LAST MATERIAL X6S
J 0
(-2100 3750);
DISPLAY 0.510638 (-2100 3750);
FORCEPROP 1 LAST VALUE 1UF
J 0
(-2100 3900);
DISPLAY 0.510638 (-2100 3900);
FORCEPROP 1 LAST PACK_TYPE 0201
J 0
(-2100 3700);
DISPLAY 0.510638 (-2100 3700);
FORCEPROP 2 LAST CDS_LIB pure_quanta
J 0
(-2150 3850);
DISPLAY INVISIBLE (-2150 3850);
FORCEPROP 1 LAST PATH I59
J 0
(-2100 4000);
DISPLAY 0.978723 (-2100 4000);
PAINT WHITE (-2100 4000);
DISPLAY INVISIBLE (-2100 4000);
FORCEPROP 1 LAST PART_NUMBER CH-10KMEE00
J 0
(-2100 3700);
DISPLAY 0.510638 (-2100 3700);
DISPLAY INVISIBLE (-2100 3700);
FORCEADD Q_CAP..1
(-1925 3850);
FORCEPROP 1 LAST LOCATION C190
J 0
(-1875 3950);
DISPLAY 0.978723 (-1875 3950);
PAINT WHITE (-1875 3950);
FORCEPROP 0 LAST $SEC 1
J 0
(-1875 4000);
DISPLAY 0.680851 (-1875 4000);
PAINT MONO (-1875 4000);
DISPLAY INVISIBLE (-1875 4000);
FORCEPROP 0 LAST CDS_SEC 1
J 0
(-1875 4000);
DISPLAY 0.680851 (-1875 4000);
DISPLAY INVISIBLE (-1875 4000);
FORCEPROP 1 LASTPIN (-1925 3950) $PN 1
J 0
(-1915 3930);
DISPLAY 0.787234 (-1915 3930);
PAINT MONO (-1915 3930);
FORCEPROP 1 LASTPIN (-1925 3750) $PN 2
J 0
(-1915 3730);
DISPLAY 0.787234 (-1915 3730);
PAINT MONO (-1915 3730);
FORCEPROP 1 LAST VOLTAGE 4V
J 0
(-1875 3850);
DISPLAY 0.510638 (-1875 3850);
FORCEPROP 1 LAST TOLERANCE 20%
J 0
(-1875 3800);
DISPLAY 0.510638 (-1875 3800);
FORCEPROP 1 LAST VALUE 1UF
J 0
(-1875 3900);
DISPLAY 0.510638 (-1875 3900);
FORCEPROP 1 LAST MATERIAL X6S
J 0
(-1875 3750);
DISPLAY 0.510638 (-1875 3750);
FORCEPROP 1 LAST PACK_TYPE 0201
J 0
(-1875 3700);
DISPLAY 0.510638 (-1875 3700);
FORCEPROP 2 LAST CDS_LIB pure_quanta
J 0
(-1925 3850);
DISPLAY INVISIBLE (-1925 3850);
FORCEPROP 1 LAST PATH I62
J 0
(-1875 4000);
DISPLAY 0.978723 (-1875 4000);
PAINT WHITE (-1875 4000);
DISPLAY INVISIBLE (-1875 4000);
FORCEPROP 1 LAST PART_NUMBER CH-10KMEE00
J 0
(-1875 3700);
DISPLAY 0.510638 (-1875 3700);
DISPLAY INVISIBLE (-1875 3700);
FORCEADD Q_CAP..1
(-1675 3850);
FORCEPROP 1 LAST LOCATION C285
J 0
(-1625 3950);
DISPLAY 0.978723 (-1625 3950);
PAINT WHITE (-1625 3950);
FORCEPROP 0 LAST $SEC 1
J 0
(-1625 4000);
DISPLAY 0.680851 (-1625 4000);
PAINT MONO (-1625 4000);
DISPLAY INVISIBLE (-1625 4000);
FORCEPROP 0 LAST CDS_SEC 1
J 0
(-1625 4000);
DISPLAY 0.680851 (-1625 4000);
DISPLAY INVISIBLE (-1625 4000);
FORCEPROP 1 LASTPIN (-1675 3950) $PN 1
J 0
(-1665 3930);
DISPLAY 0.787234 (-1665 3930);
PAINT MONO (-1665 3930);
FORCEPROP 1 LASTPIN (-1675 3750) $PN 2
J 0
(-1665 3730);
DISPLAY 0.787234 (-1665 3730);
PAINT MONO (-1665 3730);
FORCEPROP 1 LAST VOLTAGE 4V
J 0
(-1625 3850);
DISPLAY 0.510638 (-1625 3850);
FORCEPROP 1 LAST TOLERANCE 20%
J 0
(-1625 3800);
DISPLAY 0.510638 (-1625 3800);
FORCEPROP 1 LAST PACK_TYPE 0201
J 0
(-1625 3700);
DISPLAY 0.510638 (-1625 3700);
FORCEPROP 1 LAST VALUE 1UF
J 0
(-1625 3900);
DISPLAY 0.510638 (-1625 3900);
FORCEPROP 1 LAST MATERIAL X6S
J 0
(-1625 3750);
DISPLAY 0.510638 (-1625 3750);
FORCEPROP 2 LAST CDS_LIB pure_quanta
J 0
(-1675 3850);
DISPLAY INVISIBLE (-1675 3850);
FORCEPROP 1 LAST PATH I63
J 0
(-1625 4000);
DISPLAY 0.978723 (-1625 4000);
PAINT WHITE (-1625 4000);
DISPLAY INVISIBLE (-1625 4000);
FORCEPROP 1 LAST PART_NUMBER CH-10KMEE00
J 0
(-1625 3700);
DISPLAY 0.510638 (-1625 3700);
DISPLAY INVISIBLE (-1625 3700);
FORCEADD Q_CAP..1
(-2600 4475);
FORCEPROP 1 LAST LOCATION C255
J 0
(-2550 4575);
DISPLAY 0.978723 (-2550 4575);
PAINT WHITE (-2550 4575);
FORCEPROP 0 LAST $SEC 1
J 0
(-2550 4625);
DISPLAY 0.680851 (-2550 4625);
PAINT MONO (-2550 4625);
DISPLAY INVISIBLE (-2550 4625);
FORCEPROP 0 LAST CDS_SEC 1
J 0
(-2550 4625);
DISPLAY 0.680851 (-2550 4625);
DISPLAY INVISIBLE (-2550 4625);
FORCEPROP 1 LASTPIN (-2600 4575) $PN 1
J 0
(-2590 4555);
DISPLAY 0.787234 (-2590 4555);
PAINT MONO (-2590 4555);
FORCEPROP 1 LASTPIN (-2600 4375) $PN 2
J 0
(-2590 4355);
DISPLAY 0.787234 (-2590 4355);
PAINT MONO (-2590 4355);
FORCEPROP 1 LAST TOLERANCE 20%
J 0
(-2550 4425);
DISPLAY 0.510638 (-2550 4425);
FORCEPROP 1 LAST VOLTAGE 4V
J 0
(-2550 4475);
DISPLAY 0.510638 (-2550 4475);
FORCEPROP 1 LAST VALUE 22UF
J 0
(-2550 4525);
DISPLAY 0.510638 (-2550 4525);
FORCEPROP 1 LAST PACK_TYPE C0402
J 0
(-2550 4325);
DISPLAY 0.510638 (-2550 4325);
FORCEPROP 1 LAST MATERIAL X6S
J 0
(-2550 4375);
DISPLAY 0.510638 (-2550 4375);
FORCEPROP 2 LAST CDS_LIB pure_quanta
J 0
(-2600 4475);
DISPLAY INVISIBLE (-2600 4475);
FORCEPROP 1 LAST PATH I64
J 0
(-2550 4625);
DISPLAY 0.978723 (-2550 4625);
PAINT WHITE (-2550 4625);
DISPLAY INVISIBLE (-2550 4625);
FORCEPROP 1 LAST PART_NUMBER CH622KMEB02
J 0
(-2550 4325);
DISPLAY 0.978723 (-2550 4325);
DISPLAY INVISIBLE (-2550 4325);
FORCEADD Q_CAP..1
(-2375 4475);
FORCEPROP 1 LAST LOCATION C262
J 0
(-2325 4575);
DISPLAY 0.978723 (-2325 4575);
PAINT WHITE (-2325 4575);
FORCEPROP 0 LAST $SEC 1
J 0
(-2325 4625);
DISPLAY 0.680851 (-2325 4625);
PAINT MONO (-2325 4625);
DISPLAY INVISIBLE (-2325 4625);
FORCEPROP 0 LAST CDS_SEC 1
J 0
(-2325 4625);
DISPLAY 0.680851 (-2325 4625);
DISPLAY INVISIBLE (-2325 4625);
FORCEPROP 1 LASTPIN (-2375 4575) $PN 1
J 0
(-2365 4555);
DISPLAY 0.787234 (-2365 4555);
PAINT MONO (-2365 4555);
FORCEPROP 1 LASTPIN (-2375 4375) $PN 2
J 0
(-2365 4355);
DISPLAY 0.787234 (-2365 4355);
PAINT MONO (-2365 4355);
FORCEPROP 1 LAST VOLTAGE 4V
J 0
(-2325 4475);
DISPLAY 0.510638 (-2325 4475);
FORCEPROP 1 LAST VALUE 22UF
J 0
(-2325 4525);
DISPLAY 0.510638 (-2325 4525);
FORCEPROP 1 LAST MATERIAL X6S
J 0
(-2325 4375);
DISPLAY 0.510638 (-2325 4375);
FORCEPROP 1 LAST TOLERANCE 20%
J 0
(-2325 4425);
DISPLAY 0.510638 (-2325 4425);
FORCEPROP 1 LAST PACK_TYPE C0402
J 0
(-2325 4325);
DISPLAY 0.510638 (-2325 4325);
FORCEPROP 2 LAST CDS_LIB pure_quanta
J 0
(-2375 4475);
DISPLAY INVISIBLE (-2375 4475);
FORCEPROP 1 LAST PATH I65
J 0
(-2325 4625);
DISPLAY 0.978723 (-2325 4625);
PAINT WHITE (-2325 4625);
DISPLAY INVISIBLE (-2325 4625);
FORCEPROP 1 LAST PART_NUMBER CH622KMEB02
J 0
(-2325 4325);
DISPLAY 0.978723 (-2325 4325);
DISPLAY INVISIBLE (-2325 4325);
FORCEADD Q_CAP..1
(-2150 4475);
FORCEPROP 1 LAST LOCATION C259
J 0
(-2100 4575);
DISPLAY 0.978723 (-2100 4575);
PAINT WHITE (-2100 4575);
FORCEPROP 0 LAST $SEC 1
J 0
(-2100 4625);
DISPLAY 0.680851 (-2100 4625);
PAINT MONO (-2100 4625);
DISPLAY INVISIBLE (-2100 4625);
FORCEPROP 0 LAST CDS_SEC 1
J 0
(-2100 4625);
DISPLAY 0.680851 (-2100 4625);
DISPLAY INVISIBLE (-2100 4625);
FORCEPROP 1 LASTPIN (-2150 4575) $PN 1
J 0
(-2140 4555);
DISPLAY 0.787234 (-2140 4555);
PAINT MONO (-2140 4555);
FORCEPROP 1 LASTPIN (-2150 4375) $PN 2
J 0
(-2140 4355);
DISPLAY 0.787234 (-2140 4355);
PAINT MONO (-2140 4355);
FORCEPROP 1 LAST PACK_TYPE C0402
J 0
(-2100 4325);
DISPLAY 0.510638 (-2100 4325);
FORCEPROP 1 LAST MATERIAL X6S
J 0
(-2100 4375);
DISPLAY 0.510638 (-2100 4375);
FORCEPROP 1 LAST TOLERANCE 20%
J 0
(-2100 4425);
DISPLAY 0.510638 (-2100 4425);
FORCEPROP 1 LAST VALUE 22UF
J 0
(-2100 4525);
DISPLAY 0.510638 (-2100 4525);
FORCEPROP 1 LAST VOLTAGE 4V
J 0
(-2100 4475);
DISPLAY 0.510638 (-2100 4475);
FORCEPROP 2 LAST CDS_LIB pure_quanta
J 0
(-2150 4475);
DISPLAY INVISIBLE (-2150 4475);
FORCEPROP 1 LAST PATH I66
J 0
(-2100 4625);
DISPLAY 0.978723 (-2100 4625);
PAINT WHITE (-2100 4625);
DISPLAY INVISIBLE (-2100 4625);
FORCEPROP 1 LAST PART_NUMBER CH622KMEB02
J 0
(-2100 4325);
DISPLAY 0.978723 (-2100 4325);
DISPLAY INVISIBLE (-2100 4325);
FORCEADD Q_CAP..1
(-1850 4475);
FORCEPROP 1 LAST LOCATION C254
J 0
(-1800 4575);
DISPLAY 0.978723 (-1800 4575);
PAINT WHITE (-1800 4575);
FORCEPROP 0 LAST $SEC 1
J 0
(-1800 4625);
DISPLAY 0.680851 (-1800 4625);
PAINT MONO (-1800 4625);
DISPLAY INVISIBLE (-1800 4625);
FORCEPROP 0 LAST CDS_SEC 1
J 0
(-1800 4625);
DISPLAY 0.680851 (-1800 4625);
DISPLAY INVISIBLE (-1800 4625);
FORCEPROP 1 LASTPIN (-1850 4575) $PN 1
J 0
(-1840 4555);
DISPLAY 0.787234 (-1840 4555);
PAINT MONO (-1840 4555);
FORCEPROP 1 LASTPIN (-1850 4375) $PN 2
J 0
(-1840 4355);
DISPLAY 0.787234 (-1840 4355);
PAINT MONO (-1840 4355);
FORCEPROP 1 LAST MATERIAL X6S
J 0
(-1800 4375);
DISPLAY 0.510638 (-1800 4375);
FORCEPROP 1 LAST TOLERANCE 20%
J 0
(-1800 4425);
DISPLAY 0.510638 (-1800 4425);
FORCEPROP 1 LAST PACK_TYPE C0402
J 0
(-1800 4325);
DISPLAY 0.510638 (-1800 4325);
FORCEPROP 1 LAST VALUE 10UF
J 0
(-1800 4525);
DISPLAY 0.510638 (-1800 4525);
FORCEPROP 1 LAST VOLTAGE 6.3V
J 0
(-1800 4475);
DISPLAY 0.510638 (-1800 4475);
FORCEPROP 2 LAST CDS_LIB pure_quanta
J 0
(-1850 4475);
DISPLAY INVISIBLE (-1850 4475);
FORCEPROP 1 LAST PATH I67
J 0
(-1800 4625);
DISPLAY 0.978723 (-1800 4625);
PAINT WHITE (-1800 4625);
DISPLAY INVISIBLE (-1800 4625);
FORCEPROP 1 LAST PART_NUMBER CH6101MEB01
J 0
(-1800 4325);
DISPLAY 0.978723 (-1800 4325);
DISPLAY INVISIBLE (-1800 4325);
FORCEADD Q_CAP..1
(-1550 4475);
FORCEPROP 1 LAST LOCATION C286
J 0
(-1500 4575);
DISPLAY 0.978723 (-1500 4575);
PAINT WHITE (-1500 4575);
FORCEPROP 0 LAST $SEC 1
J 0
(-1500 4625);
DISPLAY 0.680851 (-1500 4625);
PAINT MONO (-1500 4625);
DISPLAY INVISIBLE (-1500 4625);
FORCEPROP 0 LAST CDS_SEC 1
J 0
(-1500 4625);
DISPLAY 0.680851 (-1500 4625);
DISPLAY INVISIBLE (-1500 4625);
FORCEPROP 1 LASTPIN (-1550 4575) $PN 1
J 0
(-1540 4555);
DISPLAY 0.787234 (-1540 4555);
PAINT MONO (-1540 4555);
FORCEPROP 1 LASTPIN (-1550 4375) $PN 2
J 0
(-1540 4355);
DISPLAY 0.787234 (-1540 4355);
PAINT MONO (-1540 4355);
FORCEPROP 1 LAST VALUE 10UF
J 0
(-1500 4525);
DISPLAY 0.510638 (-1500 4525);
FORCEPROP 1 LAST MATERIAL X6S
J 0
(-1500 4375);
DISPLAY 0.510638 (-1500 4375);
FORCEPROP 1 LAST VOLTAGE 6.3V
J 0
(-1500 4475);
DISPLAY 0.510638 (-1500 4475);
FORCEPROP 1 LAST TOLERANCE 20%
J 0
(-1500 4425);
DISPLAY 0.510638 (-1500 4425);
FORCEPROP 1 LAST PACK_TYPE C0402
J 0
(-1500 4325);
DISPLAY 0.510638 (-1500 4325);
FORCEPROP 2 LAST CDS_LIB pure_quanta
J 0
(-1550 4475);
DISPLAY INVISIBLE (-1550 4475);
FORCEPROP 1 LAST PATH I68
J 0
(-1500 4625);
DISPLAY 0.978723 (-1500 4625);
PAINT WHITE (-1500 4625);
DISPLAY INVISIBLE (-1500 4625);
FORCEPROP 1 LAST PART_NUMBER CH6101MEB01
J 0
(-1500 4325);
DISPLAY 0.978723 (-1500 4325);
DISPLAY INVISIBLE (-1500 4325);
FORCEADD VCC_CORE..1
(-3750 5125);
FORCEPROP 3 LASTPIN (-3750 5075) SIG_NAME P0V9_CPU1_RT0_2A\g
J 0
(-3740 5085);
DISPLAY 0.659574 (-3740 5085);
PAINT MONO (-3740 5085);
DISPLAY INVISIBLE (-3740 5085);
FORCEPROP 1 LAST HDL_POWER P0V9_CPU1_RT0_2A
J 1
(-3750 5175);
DISPLAY 0.617021 (-3750 5175);
PAINT GREEN (-3750 5175);
FORCEPROP 2 LAST CDS_LIB pure_quanta_power
J 0
(-3750 5125);
DISPLAY INVISIBLE (-3750 5125);
FORCEPROP 1 LAST PATH I69
J 0
(-3700 5150);
DISPLAY 0.872340 (-3700 5150);
PAINT AQUA (-3700 5150);
DISPLAY INVISIBLE (-3700 5150);
FORCEADD Q_CAP..1
(-6850 4475);
FORCEPROP 1 LAST LOCATION C121
J 0
(-6800 4575);
DISPLAY 0.638298 (-6800 4575);
PAINT WHITE (-6800 4575);
FORCEPROP 0 LAST $SEC 1
J 0
(-6800 4600);
DISPLAY 0.680851 (-6800 4600);
PAINT MONO (-6800 4600);
DISPLAY INVISIBLE (-6800 4600);
FORCEPROP 0 LAST CDS_SEC 1
J 0
(-6800 4600);
DISPLAY 0.680851 (-6800 4600);
DISPLAY INVISIBLE (-6800 4600);
FORCEPROP 1 LASTPIN (-6850 4575) $PN 1
J 0
(-6840 4555);
DISPLAY 0.787234 (-6840 4555);
PAINT MONO (-6840 4555);
FORCEPROP 1 LASTPIN (-6850 4375) $PN 2
J 0
(-6840 4355);
DISPLAY 0.787234 (-6840 4355);
PAINT MONO (-6840 4355);
FORCEPROP 1 LAST VOLTAGE 6.3V
J 0
(-6800 4475);
DISPLAY 0.510638 (-6800 4475);
FORCEPROP 1 LAST VALUE 4.7UF
J 0
(-6800 4525);
DISPLAY 0.510638 (-6800 4525);
FORCEPROP 1 LAST TOLERANCE 20%
J 0
(-6800 4425);
DISPLAY 0.510638 (-6800 4425);
FORCEPROP 1 LAST MATERIAL X6S
J 0
(-6800 4375);
DISPLAY 0.510638 (-6800 4375);
FORCEPROP 1 LAST PACK_TYPE 0402
J 0
(-6800 4325);
DISPLAY 0.510638 (-6800 4325);
FORCEPROP 2 LAST CDS_LIB pure_quanta
J 0
(-6850 4475);
DISPLAY INVISIBLE (-6850 4475);
FORCEPROP 1 LAST PATH I7
J 0
(-6800 4625);
DISPLAY 0.978723 (-6800 4625);
PAINT WHITE (-6800 4625);
DISPLAY INVISIBLE (-6800 4625);
FORCEPROP 1 LAST PART_NUMBER CH5471MEB01
J 0
(-6800 4325);
DISPLAY 0.978723 (-6800 4325);
DISPLAY INVISIBLE (-6800 4325);
FORCEADD Q_CAP..1
(-3750 3850);
FORCEPROP 1 LAST LOCATION C250
J 0
(-3700 3950);
DISPLAY 0.978723 (-3700 3950);
PAINT WHITE (-3700 3950);
FORCEPROP 0 LAST $SEC 1
J 0
(-3700 4000);
DISPLAY 0.680851 (-3700 4000);
PAINT MONO (-3700 4000);
DISPLAY INVISIBLE (-3700 4000);
FORCEPROP 0 LAST CDS_SEC 1
J 0
(-3700 4000);
DISPLAY 0.680851 (-3700 4000);
DISPLAY INVISIBLE (-3700 4000);
FORCEPROP 1 LASTPIN (-3750 3950) $PN 1
J 0
(-3740 3930);
DISPLAY 0.787234 (-3740 3930);
PAINT MONO (-3740 3930);
FORCEPROP 1 LASTPIN (-3750 3750) $PN 2
J 0
(-3740 3730);
DISPLAY 0.787234 (-3740 3730);
PAINT MONO (-3740 3730);
FORCEPROP 1 LAST TOLERANCE 20%
J 0
(-3700 3800);
DISPLAY 0.510638 (-3700 3800);
FORCEPROP 1 LAST MATERIAL X6S
J 0
(-3700 3750);
DISPLAY 0.510638 (-3700 3750);
FORCEPROP 1 LAST PACK_TYPE C0402
J 0
(-3700 3700);
DISPLAY 0.510638 (-3700 3700);
FORCEPROP 1 LAST VOLTAGE 6.3V
J 0
(-3700 3850);
DISPLAY 0.510638 (-3700 3850);
FORCEPROP 1 LAST VALUE 10UF
J 0
(-3700 3900);
DISPLAY 0.510638 (-3700 3900);
FORCEPROP 2 LAST CDS_LIB pure_quanta
J 0
(-3750 3850);
DISPLAY INVISIBLE (-3750 3850);
FORCEPROP 1 LAST PATH I70
J 0
(-3700 4000);
DISPLAY 0.978723 (-3700 4000);
PAINT WHITE (-3700 4000);
DISPLAY INVISIBLE (-3700 4000);
FORCEPROP 1 LAST PART_NUMBER CH6101MEB01
J 0
(-3700 3700);
DISPLAY 0.978723 (-3700 3700);
DISPLAY INVISIBLE (-3700 3700);
FORCEADD Q_CAP..1
(-3525 3850);
FORCEPROP 1 LAST LOCATION C269
J 0
(-3475 3950);
DISPLAY 0.978723 (-3475 3950);
PAINT WHITE (-3475 3950);
FORCEPROP 0 LAST $SEC 1
J 0
(-3475 4000);
DISPLAY 0.680851 (-3475 4000);
PAINT MONO (-3475 4000);
DISPLAY INVISIBLE (-3475 4000);
FORCEPROP 0 LAST CDS_SEC 1
J 0
(-3475 4000);
DISPLAY 0.680851 (-3475 4000);
DISPLAY INVISIBLE (-3475 4000);
FORCEPROP 1 LASTPIN (-3525 3950) $PN 1
J 0
(-3515 3930);
DISPLAY 0.787234 (-3515 3930);
PAINT MONO (-3515 3930);
FORCEPROP 1 LASTPIN (-3525 3750) $PN 2
J 0
(-3515 3730);
DISPLAY 0.787234 (-3515 3730);
PAINT MONO (-3515 3730);
FORCEPROP 1 LAST PACK_TYPE C0402
J 0
(-3475 3700);
DISPLAY 0.510638 (-3475 3700);
FORCEPROP 1 LAST VOLTAGE 6.3V
J 0
(-3475 3850);
DISPLAY 0.510638 (-3475 3850);
FORCEPROP 1 LAST TOLERANCE 20%
J 0
(-3475 3800);
DISPLAY 0.510638 (-3475 3800);
FORCEPROP 1 LAST VALUE 10UF
J 0
(-3475 3900);
DISPLAY 0.510638 (-3475 3900);
FORCEPROP 1 LAST MATERIAL X6S
J 0
(-3475 3750);
DISPLAY 0.510638 (-3475 3750);
FORCEPROP 2 LAST CDS_LIB pure_quanta
J 0
(-3525 3850);
DISPLAY INVISIBLE (-3525 3850);
FORCEPROP 1 LAST PATH I71
J 0
(-3475 4000);
DISPLAY 0.978723 (-3475 4000);
PAINT WHITE (-3475 4000);
DISPLAY INVISIBLE (-3475 4000);
FORCEPROP 1 LAST PART_NUMBER CH6101MEB01
J 0
(-3475 3700);
DISPLAY 0.978723 (-3475 3700);
DISPLAY INVISIBLE (-3475 3700);
FORCEADD Q_CAP..1
(-3300 3850);
FORCEPROP 1 LAST LOCATION C241
J 0
(-3250 3950);
DISPLAY 0.978723 (-3250 3950);
PAINT WHITE (-3250 3950);
FORCEPROP 0 LAST $SEC 1
J 0
(-3250 4000);
DISPLAY 0.680851 (-3250 4000);
PAINT MONO (-3250 4000);
DISPLAY INVISIBLE (-3250 4000);
FORCEPROP 0 LAST CDS_SEC 1
J 0
(-3250 4000);
DISPLAY 0.680851 (-3250 4000);
DISPLAY INVISIBLE (-3250 4000);
FORCEPROP 1 LASTPIN (-3300 3950) $PN 1
J 0
(-3290 3930);
DISPLAY 0.787234 (-3290 3930);
PAINT MONO (-3290 3930);
FORCEPROP 1 LASTPIN (-3300 3750) $PN 2
J 0
(-3290 3730);
DISPLAY 0.787234 (-3290 3730);
PAINT MONO (-3290 3730);
FORCEPROP 1 LAST VOLTAGE 6.3V
J 0
(-3250 3850);
DISPLAY 0.510638 (-3250 3850);
FORCEPROP 1 LAST PACK_TYPE 0402
J 0
(-3250 3700);
DISPLAY 0.510638 (-3250 3700);
FORCEPROP 1 LAST MATERIAL X6S
J 0
(-3250 3750);
DISPLAY 0.510638 (-3250 3750);
FORCEPROP 1 LAST TOLERANCE 20%
J 0
(-3250 3800);
DISPLAY 0.510638 (-3250 3800);
FORCEPROP 1 LAST VALUE 4.7UF
J 0
(-3250 3900);
DISPLAY 0.510638 (-3250 3900);
FORCEPROP 2 LAST CDS_LIB pure_quanta
J 0
(-3300 3850);
DISPLAY INVISIBLE (-3300 3850);
FORCEPROP 1 LAST PATH I72
J 0
(-3250 4000);
DISPLAY 0.978723 (-3250 4000);
PAINT WHITE (-3250 4000);
DISPLAY INVISIBLE (-3250 4000);
FORCEPROP 1 LAST PART_NUMBER CH5471MEB01
J 0
(-3250 3700);
DISPLAY 0.978723 (-3250 3700);
DISPLAY INVISIBLE (-3250 3700);
FORCEADD Q_CAP..1
(-3075 4475);
FORCEPROP 1 LAST LOCATION C247
J 0
(-3025 4575);
DISPLAY 0.978723 (-3025 4575);
PAINT WHITE (-3025 4575);
FORCEPROP 0 LAST $SEC 1
J 0
(-3025 4625);
DISPLAY 0.680851 (-3025 4625);
PAINT MONO (-3025 4625);
DISPLAY INVISIBLE (-3025 4625);
FORCEPROP 0 LAST CDS_SEC 1
J 0
(-3025 4625);
DISPLAY 0.680851 (-3025 4625);
DISPLAY INVISIBLE (-3025 4625);
FORCEPROP 1 LASTPIN (-3075 4575) $PN 1
J 0
(-3065 4555);
DISPLAY 0.787234 (-3065 4555);
PAINT MONO (-3065 4555);
FORCEPROP 1 LASTPIN (-3075 4375) $PN 2
J 0
(-3065 4355);
DISPLAY 0.787234 (-3065 4355);
PAINT MONO (-3065 4355);
FORCEPROP 1 LAST TOLERANCE 20%
J 0
(-3025 4425);
DISPLAY 0.510638 (-3025 4425);
FORCEPROP 1 LAST VALUE 100UF
J 0
(-3025 4525);
DISPLAY 0.510638 (-3025 4525);
FORCEPROP 1 LAST PACK_TYPE C0805
J 0
(-3025 4325);
DISPLAY 0.510638 (-3025 4325);
FORCEPROP 1 LAST MATERIAL X6S
J 0
(-3025 4375);
DISPLAY 0.510638 (-3025 4375);
FORCEPROP 1 LAST VOLTAGE 4V
J 0
(-3025 4475);
DISPLAY 0.510638 (-3025 4475);
FORCEPROP 2 LAST CDS_LIB pure_quanta
J 0
(-3075 4475);
DISPLAY INVISIBLE (-3075 4475);
FORCEPROP 1 LAST PATH I73
J 0
(-3025 4625);
DISPLAY 0.978723 (-3025 4625);
PAINT WHITE (-3025 4625);
DISPLAY INVISIBLE (-3025 4625);
FORCEPROP 1 LAST PART_NUMBER CH710KMEA01
J 0
(-3025 4325);
DISPLAY 0.404255 (-3025 4325);
DISPLAY INVISIBLE (-3025 4325);
FORCEADD Q_INDUCTOR..1
(-4100 4750);
FORCEPROP 1 LAST LOCATION L4
J 0
(-4225 4910);
DISPLAY 0.723404 (-4225 4910);
PAINT GREEN (-4225 4910);
FORCEPROP 0 LAST $SEC 1
J 0
(-4225 5050);
DISPLAY 0.680851 (-4225 5050);
PAINT MONO (-4225 5050);
DISPLAY INVISIBLE (-4225 5050);
FORCEPROP 0 LAST CDS_SEC 1
J 0
(-4225 5050);
DISPLAY 0.680851 (-4225 5050);
DISPLAY INVISIBLE (-4225 5050);
FORCEPROP 0 LASTPIN (-4200 4725) $PN 1
J 2
(-4210 4735);
DISPLAY 0.680851 (-4210 4735);
PAINT MONO (-4210 4735);
FORCEPROP 0 LASTPIN (-4000 4725) $PN 2
J 0
(-3990 4735);
DISPLAY 0.680851 (-3990 4735);
PAINT MONO (-3990 4735);
FORCEPROP 1 LAST MATERIAL IND
J 0
(-4225 4805);
DISPLAY 0.723404 (-4225 4805);
PAINT GREEN (-4225 4805);
FORCEPROP 2 LAST VALUE 100NH/16A
J 0
(-4225 5000);
DISPLAY 0.680851 (-4225 5000);
FORCEPROP 2 LAST PACK_TYPE SMLF
J 0
(-4225 4950);
DISPLAY 0.680851 (-4225 4950);
FORCEPROP 1 LAST NEEDS_NO_SIZE TRUE
J 0
(-4100 4750);
DISPLAY 0.468085 (-4100 4750);
PAINT GREEN (-4100 4750);
DISPLAY INVISIBLE (-4100 4750);
FORCEPROP 2 LAST CDS_LIB pure_quanta
J 0
(-4100 4750);
DISPLAY INVISIBLE (-4100 4750);
FORCEPROP 1 LAST PATH I74
J 0
(-4025 4805);
DISPLAY 0.723404 (-4025 4805);
PAINT GREEN (-4025 4805);
DISPLAY INVISIBLE (-4025 4805);
FORCEPROP 1 LAST PART_NUMBER CV+10G0MZ04
J 0
(-4225 4860);
DISPLAY 0.723404 (-4225 4860);
PAINT GREEN (-4225 4860);
DISPLAY INVISIBLE (-4225 4860);
FORCEADD Q_CAP..1
(-1400 5700);
FORCEPROP 1 LAST LOCATION C189
J 0
(-1350 5800);
DISPLAY 0.978723 (-1350 5800);
PAINT WHITE (-1350 5800);
FORCEPROP 0 LAST $SEC 1
J 0
(-1350 5850);
DISPLAY 0.680851 (-1350 5850);
PAINT MONO (-1350 5850);
DISPLAY INVISIBLE (-1350 5850);
FORCEPROP 0 LAST CDS_SEC 1
J 0
(-1350 5850);
DISPLAY 0.680851 (-1350 5850);
DISPLAY INVISIBLE (-1350 5850);
FORCEPROP 1 LASTPIN (-1400 5800) $PN 1
J 0
(-1390 5780);
DISPLAY 0.787234 (-1390 5780);
PAINT MONO (-1390 5780);
FORCEPROP 1 LASTPIN (-1400 5600) $PN 2
J 0
(-1390 5580);
DISPLAY 0.787234 (-1390 5580);
PAINT MONO (-1390 5580);
FORCEPROP 1 LAST VALUE 0.1UF
J 0
(-1350 5750);
DISPLAY 0.638298 (-1350 5750);
FORCEPROP 1 LAST PACK_TYPE C0201
J 0
(-1350 5550);
DISPLAY 0.638298 (-1350 5550);
FORCEPROP 1 LAST MATERIAL X7S
J 0
(-1350 5600);
DISPLAY 0.638298 (-1350 5600);
FORCEPROP 1 LAST VOLTAGE 10V
J 0
(-1350 5700);
DISPLAY 0.638298 (-1350 5700);
FORCEPROP 1 LAST TOLERANCE 10%
J 0
(-1350 5650);
DISPLAY 0.638298 (-1350 5650);
FORCEPROP 2 LAST CDS_LIB pure_quanta
J 0
(-1400 5700);
DISPLAY INVISIBLE (-1400 5700);
FORCEPROP 1 LAST PATH I75
J 0
(-1350 5850);
DISPLAY 0.978723 (-1350 5850);
PAINT WHITE (-1350 5850);
DISPLAY INVISIBLE (-1350 5850);
FORCEPROP 1 LAST PART_NUMBER CH4102K6E00
J 0
(-1350 5550);
DISPLAY 0.978723 (-1350 5550);
DISPLAY INVISIBLE (-1350 5550);
FORCEADD Q_CAP..1
(-1675 5700);
FORCEPROP 1 LAST LOCATION C266
J 0
(-1625 5800);
DISPLAY 0.978723 (-1625 5800);
PAINT WHITE (-1625 5800);
FORCEPROP 0 LAST $SEC 1
J 0
(-1625 5850);
DISPLAY 0.680851 (-1625 5850);
PAINT MONO (-1625 5850);
DISPLAY INVISIBLE (-1625 5850);
FORCEPROP 0 LAST CDS_SEC 1
J 0
(-1625 5850);
DISPLAY 0.680851 (-1625 5850);
DISPLAY INVISIBLE (-1625 5850);
FORCEPROP 1 LASTPIN (-1675 5800) $PN 1
J 0
(-1665 5780);
DISPLAY 0.787234 (-1665 5780);
PAINT MONO (-1665 5780);
FORCEPROP 1 LASTPIN (-1675 5600) $PN 2
J 0
(-1665 5580);
DISPLAY 0.787234 (-1665 5580);
PAINT MONO (-1665 5580);
FORCEPROP 1 LAST VALUE 0.1UF
J 0
(-1625 5750);
DISPLAY 0.638298 (-1625 5750);
FORCEPROP 1 LAST VOLTAGE 10V
J 0
(-1625 5700);
DISPLAY 0.638298 (-1625 5700);
FORCEPROP 1 LAST MATERIAL X7S
J 0
(-1625 5600);
DISPLAY 0.638298 (-1625 5600);
FORCEPROP 1 LAST PACK_TYPE C0201
J 0
(-1625 5550);
DISPLAY 0.638298 (-1625 5550);
FORCEPROP 1 LAST TOLERANCE 10%
J 0
(-1625 5650);
DISPLAY 0.638298 (-1625 5650);
FORCEPROP 2 LAST CDS_LIB pure_quanta
J 0
(-1675 5700);
DISPLAY INVISIBLE (-1675 5700);
FORCEPROP 1 LAST PATH I76
J 0
(-1625 5850);
DISPLAY 0.978723 (-1625 5850);
PAINT WHITE (-1625 5850);
DISPLAY INVISIBLE (-1625 5850);
FORCEPROP 1 LAST PART_NUMBER CH4102K6E00
J 0
(-1625 5550);
DISPLAY 0.978723 (-1625 5550);
DISPLAY INVISIBLE (-1625 5550);
FORCEADD Q_CAP..1
(-1925 5700);
FORCEPROP 1 LAST LOCATION C139
J 0
(-1875 5800);
DISPLAY 0.978723 (-1875 5800);
PAINT WHITE (-1875 5800);
FORCEPROP 0 LAST $SEC 1
J 0
(-1875 5850);
DISPLAY 0.680851 (-1875 5850);
PAINT MONO (-1875 5850);
DISPLAY INVISIBLE (-1875 5850);
FORCEPROP 0 LAST CDS_SEC 1
J 0
(-1875 5850);
DISPLAY 0.680851 (-1875 5850);
DISPLAY INVISIBLE (-1875 5850);
FORCEPROP 1 LASTPIN (-1925 5800) $PN 1
J 0
(-1915 5780);
DISPLAY 0.787234 (-1915 5780);
PAINT MONO (-1915 5780);
FORCEPROP 1 LASTPIN (-1925 5600) $PN 2
J 0
(-1915 5580);
DISPLAY 0.787234 (-1915 5580);
PAINT MONO (-1915 5580);
FORCEPROP 1 LAST VOLTAGE 10V
J 0
(-1875 5700);
DISPLAY 0.638298 (-1875 5700);
FORCEPROP 1 LAST VALUE 0.1UF
J 0
(-1875 5750);
DISPLAY 0.638298 (-1875 5750);
FORCEPROP 1 LAST PACK_TYPE C0201
J 0
(-1875 5550);
DISPLAY 0.638298 (-1875 5550);
FORCEPROP 1 LAST MATERIAL X7S
J 0
(-1875 5600);
DISPLAY 0.638298 (-1875 5600);
FORCEPROP 1 LAST TOLERANCE 10%
J 0
(-1875 5650);
DISPLAY 0.638298 (-1875 5650);
FORCEPROP 2 LAST CDS_LIB pure_quanta
J 0
(-1925 5700);
DISPLAY INVISIBLE (-1925 5700);
FORCEPROP 1 LAST PATH I77
J 0
(-1875 5850);
DISPLAY 0.978723 (-1875 5850);
PAINT WHITE (-1875 5850);
DISPLAY INVISIBLE (-1875 5850);
FORCEPROP 1 LAST PART_NUMBER CH4102K6E00
J 0
(-1875 5550);
DISPLAY 0.978723 (-1875 5550);
DISPLAY INVISIBLE (-1875 5550);
FORCEADD Q_CAP..1
(-2200 5700);
FORCEPROP 1 LAST LOCATION C137
J 0
(-2150 5800);
DISPLAY 0.978723 (-2150 5800);
PAINT WHITE (-2150 5800);
FORCEPROP 0 LAST $SEC 1
J 0
(-2150 5850);
DISPLAY 0.680851 (-2150 5850);
PAINT MONO (-2150 5850);
DISPLAY INVISIBLE (-2150 5850);
FORCEPROP 0 LAST CDS_SEC 1
J 0
(-2150 5850);
DISPLAY 0.680851 (-2150 5850);
DISPLAY INVISIBLE (-2150 5850);
FORCEPROP 1 LASTPIN (-2200 5800) $PN 1
J 0
(-2190 5780);
DISPLAY 0.787234 (-2190 5780);
PAINT MONO (-2190 5780);
FORCEPROP 1 LASTPIN (-2200 5600) $PN 2
J 0
(-2190 5580);
DISPLAY 0.787234 (-2190 5580);
PAINT MONO (-2190 5580);
FORCEPROP 1 LAST MATERIAL X7S
J 0
(-2150 5600);
DISPLAY 0.638298 (-2150 5600);
FORCEPROP 1 LAST PACK_TYPE C0201
J 0
(-2150 5550);
DISPLAY 0.638298 (-2150 5550);
FORCEPROP 1 LAST TOLERANCE 10%
J 0
(-2150 5650);
DISPLAY 0.638298 (-2150 5650);
FORCEPROP 1 LAST VOLTAGE 10V
J 0
(-2150 5700);
DISPLAY 0.638298 (-2150 5700);
FORCEPROP 1 LAST VALUE 0.1UF
J 0
(-2150 5750);
DISPLAY 0.638298 (-2150 5750);
FORCEPROP 2 LAST CDS_LIB pure_quanta
J 0
(-2200 5700);
DISPLAY INVISIBLE (-2200 5700);
FORCEPROP 1 LAST PATH I78
J 0
(-2150 5850);
DISPLAY 0.978723 (-2150 5850);
PAINT WHITE (-2150 5850);
DISPLAY INVISIBLE (-2150 5850);
FORCEPROP 1 LAST PART_NUMBER CH4102K6E00
J 0
(-2150 5550);
DISPLAY 0.978723 (-2150 5550);
DISPLAY INVISIBLE (-2150 5550);
FORCEADD UNIVERSAL_GND..1
(-1475 5300);
FORCEPROP 3 LASTPIN (-1475 5350) SIG_NAME GND\g
J 0
(-1465 5360);
DISPLAY 0.659574 (-1465 5360);
PAINT MONO (-1465 5360);
DISPLAY INVISIBLE (-1465 5360);
FORCEPROP 2 LAST CDS_LIB pure_quanta_power
J 0
(-1475 5300);
DISPLAY INVISIBLE (-1475 5300);
FORCEPROP 1 LAST HDL_POWER GND
J 1
(-1450 5225);
DISPLAY 0.872340 (-1450 5225);
PAINT GREEN (-1450 5225);
DISPLAY INVISIBLE (-1450 5225);
FORCEPROP 1 LAST PATH I79
J 0
(-1400 5300);
DISPLAY 0.872340 (-1400 5300);
PAINT AQUA (-1400 5300);
DISPLAY INVISIBLE (-1400 5300);
FORCEADD Q_CAP..1
(-2950 2525);
FORCEPROP 1 LAST LOCATION C282
J 0
(-2900 2625);
DISPLAY 0.978723 (-2900 2625);
PAINT WHITE (-2900 2625);
FORCEPROP 0 LAST $SEC 1
J 0
(-2900 2675);
DISPLAY 0.680851 (-2900 2675);
PAINT MONO (-2900 2675);
DISPLAY INVISIBLE (-2900 2675);
FORCEPROP 0 LAST CDS_SEC 1
J 0
(-2900 2675);
DISPLAY 0.680851 (-2900 2675);
DISPLAY INVISIBLE (-2900 2675);
FORCEPROP 1 LASTPIN (-2950 2625) $PN 1
J 0
(-2940 2605);
DISPLAY 0.787234 (-2940 2605);
PAINT MONO (-2940 2605);
FORCEPROP 1 LASTPIN (-2950 2425) $PN 2
J 0
(-2940 2405);
DISPLAY 0.787234 (-2940 2405);
PAINT MONO (-2940 2405);
FORCEPROP 1 LAST TOLERANCE 10%
J 0
(-2900 2475);
DISPLAY 0.638298 (-2900 2475);
FORCEPROP 1 LAST VOLTAGE 10V
J 0
(-2900 2525);
DISPLAY 0.638298 (-2900 2525);
FORCEPROP 1 LAST MATERIAL X7S
J 0
(-2900 2425);
DISPLAY 0.638298 (-2900 2425);
FORCEPROP 1 LAST PACK_TYPE C0201
J 0
(-2900 2375);
DISPLAY 0.638298 (-2900 2375);
FORCEPROP 1 LAST VALUE 0.1UF
J 0
(-2900 2575);
DISPLAY 0.638298 (-2900 2575);
FORCEPROP 2 LAST CDS_LIB pure_quanta
J 0
(-2950 2525);
DISPLAY INVISIBLE (-2950 2525);
FORCEPROP 1 LAST PATH I80
J 0
(-2900 2675);
DISPLAY 0.978723 (-2900 2675);
PAINT WHITE (-2900 2675);
DISPLAY INVISIBLE (-2900 2675);
FORCEPROP 1 LAST PART_NUMBER CH4102K6E00
J 0
(-2900 2375);
DISPLAY 0.978723 (-2900 2375);
DISPLAY INVISIBLE (-2900 2375);
FORCEADD Q_CAP..1
(-3175 2525);
FORCEPROP 1 LAST LOCATION C264
J 0
(-3125 2625);
DISPLAY 0.978723 (-3125 2625);
PAINT WHITE (-3125 2625);
FORCEPROP 0 LAST $SEC 1
J 0
(-3125 2675);
DISPLAY 0.680851 (-3125 2675);
PAINT MONO (-3125 2675);
DISPLAY INVISIBLE (-3125 2675);
FORCEPROP 0 LAST CDS_SEC 1
J 0
(-3125 2675);
DISPLAY 0.680851 (-3125 2675);
DISPLAY INVISIBLE (-3125 2675);
FORCEPROP 1 LASTPIN (-3175 2625) $PN 1
J 0
(-3165 2605);
DISPLAY 0.787234 (-3165 2605);
PAINT MONO (-3165 2605);
FORCEPROP 1 LASTPIN (-3175 2425) $PN 2
J 0
(-3165 2405);
DISPLAY 0.787234 (-3165 2405);
PAINT MONO (-3165 2405);
FORCEPROP 1 LAST PACK_TYPE C0201
J 0
(-3125 2375);
DISPLAY 0.638298 (-3125 2375);
FORCEPROP 1 LAST VALUE 0.1UF
J 0
(-3125 2575);
DISPLAY 0.638298 (-3125 2575);
FORCEPROP 1 LAST MATERIAL X7S
J 0
(-3125 2425);
DISPLAY 0.638298 (-3125 2425);
FORCEPROP 1 LAST TOLERANCE 10%
J 0
(-3125 2475);
DISPLAY 0.638298 (-3125 2475);
FORCEPROP 1 LAST VOLTAGE 10V
J 0
(-3125 2525);
DISPLAY 0.638298 (-3125 2525);
FORCEPROP 2 LAST CDS_LIB pure_quanta
J 0
(-3175 2525);
DISPLAY INVISIBLE (-3175 2525);
FORCEPROP 1 LAST PATH I81
J 0
(-3125 2675);
DISPLAY 0.978723 (-3125 2675);
PAINT WHITE (-3125 2675);
DISPLAY INVISIBLE (-3125 2675);
FORCEPROP 1 LAST PART_NUMBER CH4102K6E00
J 0
(-3125 2375);
DISPLAY 0.978723 (-3125 2375);
DISPLAY INVISIBLE (-3125 2375);
FORCEADD Q_CAP..1
(-3475 2525);
FORCEPROP 1 LAST LOCATION C141
J 0
(-3425 2625);
DISPLAY 0.978723 (-3425 2625);
PAINT WHITE (-3425 2625);
FORCEPROP 0 LAST $SEC 1
J 0
(-3425 2675);
DISPLAY 0.680851 (-3425 2675);
PAINT MONO (-3425 2675);
DISPLAY INVISIBLE (-3425 2675);
FORCEPROP 0 LAST CDS_SEC 1
J 0
(-3425 2675);
DISPLAY 0.680851 (-3425 2675);
DISPLAY INVISIBLE (-3425 2675);
FORCEPROP 1 LASTPIN (-3475 2625) $PN 1
J 0
(-3465 2605);
DISPLAY 0.787234 (-3465 2605);
PAINT MONO (-3465 2605);
FORCEPROP 1 LASTPIN (-3475 2425) $PN 2
J 0
(-3465 2405);
DISPLAY 0.787234 (-3465 2405);
PAINT MONO (-3465 2405);
FORCEPROP 1 LAST VALUE 0.1UF
J 0
(-3425 2575);
DISPLAY 0.638298 (-3425 2575);
FORCEPROP 1 LAST MATERIAL X7S
J 0
(-3425 2425);
DISPLAY 0.638298 (-3425 2425);
FORCEPROP 1 LAST PACK_TYPE C0201
J 0
(-3425 2375);
DISPLAY 0.638298 (-3425 2375);
FORCEPROP 1 LAST VOLTAGE 10V
J 0
(-3425 2525);
DISPLAY 0.638298 (-3425 2525);
FORCEPROP 1 LAST TOLERANCE 10%
J 0
(-3425 2475);
DISPLAY 0.638298 (-3425 2475);
FORCEPROP 2 LAST CDS_LIB pure_quanta
J 0
(-3475 2525);
DISPLAY INVISIBLE (-3475 2525);
FORCEPROP 1 LAST PATH I82
J 0
(-3425 2675);
DISPLAY 0.978723 (-3425 2675);
PAINT WHITE (-3425 2675);
DISPLAY INVISIBLE (-3425 2675);
FORCEPROP 1 LAST PART_NUMBER CH4102K6E00
J 0
(-3425 2375);
DISPLAY 0.978723 (-3425 2375);
DISPLAY INVISIBLE (-3425 2375);
FORCEADD Q_CAP..1
(-1650 2525);
FORCEPROP 1 LAST LOCATION C192
J 0
(-1600 2625);
DISPLAY 0.978723 (-1600 2625);
PAINT WHITE (-1600 2625);
FORCEPROP 0 LAST $SEC 1
J 0
(-1600 2675);
DISPLAY 0.680851 (-1600 2675);
PAINT MONO (-1600 2675);
DISPLAY INVISIBLE (-1600 2675);
FORCEPROP 0 LAST CDS_SEC 1
J 0
(-1600 2675);
DISPLAY 0.680851 (-1600 2675);
DISPLAY INVISIBLE (-1600 2675);
FORCEPROP 1 LASTPIN (-1650 2625) $PN 1
J 0
(-1640 2605);
DISPLAY 0.787234 (-1640 2605);
PAINT MONO (-1640 2605);
FORCEPROP 1 LASTPIN (-1650 2425) $PN 2
J 0
(-1640 2405);
DISPLAY 0.787234 (-1640 2405);
PAINT MONO (-1640 2405);
FORCEPROP 1 LAST MATERIAL X7S
J 0
(-1600 2425);
DISPLAY 0.638298 (-1600 2425);
FORCEPROP 1 LAST PACK_TYPE C0201
J 0
(-1600 2375);
DISPLAY 0.638298 (-1600 2375);
FORCEPROP 1 LAST TOLERANCE 10%
J 0
(-1600 2475);
DISPLAY 0.638298 (-1600 2475);
FORCEPROP 1 LAST VALUE 0.1UF
J 0
(-1600 2575);
DISPLAY 0.638298 (-1600 2575);
FORCEPROP 1 LAST VOLTAGE 10V
J 0
(-1600 2525);
DISPLAY 0.638298 (-1600 2525);
FORCEPROP 2 LAST CDS_LIB pure_quanta
J 0
(-1650 2525);
DISPLAY INVISIBLE (-1650 2525);
FORCEPROP 1 LAST PATH I83
J 0
(-1600 2675);
DISPLAY 0.978723 (-1600 2675);
PAINT WHITE (-1600 2675);
DISPLAY INVISIBLE (-1600 2675);
FORCEPROP 1 LAST PART_NUMBER CH4102K6E00
J 0
(-1600 2375);
DISPLAY 0.978723 (-1600 2375);
DISPLAY INVISIBLE (-1600 2375);
FORCEADD Q_CAP..1
(-1900 2525);
FORCEPROP 1 LAST LOCATION C260
J 0
(-1850 2625);
DISPLAY 0.978723 (-1850 2625);
PAINT WHITE (-1850 2625);
FORCEPROP 0 LAST $SEC 1
J 0
(-1850 2675);
DISPLAY 0.680851 (-1850 2675);
PAINT MONO (-1850 2675);
DISPLAY INVISIBLE (-1850 2675);
FORCEPROP 0 LAST CDS_SEC 1
J 0
(-1850 2675);
DISPLAY 0.680851 (-1850 2675);
DISPLAY INVISIBLE (-1850 2675);
FORCEPROP 1 LASTPIN (-1900 2625) $PN 1
J 0
(-1890 2605);
DISPLAY 0.787234 (-1890 2605);
PAINT MONO (-1890 2605);
FORCEPROP 1 LASTPIN (-1900 2425) $PN 2
J 0
(-1890 2405);
DISPLAY 0.787234 (-1890 2405);
PAINT MONO (-1890 2405);
FORCEPROP 1 LAST PACK_TYPE C0201
J 0
(-1850 2375);
DISPLAY 0.638298 (-1850 2375);
FORCEPROP 1 LAST MATERIAL X7S
J 0
(-1850 2425);
DISPLAY 0.638298 (-1850 2425);
FORCEPROP 1 LAST VALUE 0.1UF
J 0
(-1850 2575);
DISPLAY 0.638298 (-1850 2575);
FORCEPROP 1 LAST VOLTAGE 10V
J 0
(-1850 2525);
DISPLAY 0.638298 (-1850 2525);
FORCEPROP 1 LAST TOLERANCE 10%
J 0
(-1850 2475);
DISPLAY 0.638298 (-1850 2475);
FORCEPROP 2 LAST CDS_LIB pure_quanta
J 0
(-1900 2525);
DISPLAY INVISIBLE (-1900 2525);
FORCEPROP 1 LAST PATH I84
J 0
(-1850 2675);
DISPLAY 0.978723 (-1850 2675);
PAINT WHITE (-1850 2675);
DISPLAY INVISIBLE (-1850 2675);
FORCEPROP 1 LAST PART_NUMBER CH4102K6E00
J 0
(-1850 2375);
DISPLAY 0.978723 (-1850 2375);
DISPLAY INVISIBLE (-1850 2375);
FORCEADD Q_CAP..1
(-2175 2525);
FORCEPROP 1 LAST LOCATION C184
J 0
(-2125 2625);
DISPLAY 0.978723 (-2125 2625);
PAINT WHITE (-2125 2625);
FORCEPROP 0 LAST $SEC 1
J 0
(-2125 2675);
DISPLAY 0.680851 (-2125 2675);
PAINT MONO (-2125 2675);
DISPLAY INVISIBLE (-2125 2675);
FORCEPROP 0 LAST CDS_SEC 1
J 0
(-2125 2675);
DISPLAY 0.680851 (-2125 2675);
DISPLAY INVISIBLE (-2125 2675);
FORCEPROP 1 LASTPIN (-2175 2625) $PN 1
J 0
(-2165 2605);
DISPLAY 0.787234 (-2165 2605);
PAINT MONO (-2165 2605);
FORCEPROP 1 LASTPIN (-2175 2425) $PN 2
J 0
(-2165 2405);
DISPLAY 0.787234 (-2165 2405);
PAINT MONO (-2165 2405);
FORCEPROP 1 LAST PACK_TYPE C0201
J 0
(-2125 2375);
DISPLAY 0.638298 (-2125 2375);
FORCEPROP 1 LAST MATERIAL X7S
J 0
(-2125 2425);
DISPLAY 0.638298 (-2125 2425);
FORCEPROP 1 LAST VOLTAGE 10V
J 0
(-2125 2525);
DISPLAY 0.638298 (-2125 2525);
FORCEPROP 1 LAST TOLERANCE 10%
J 0
(-2125 2475);
DISPLAY 0.638298 (-2125 2475);
FORCEPROP 1 LAST VALUE 0.1UF
J 0
(-2125 2575);
DISPLAY 0.638298 (-2125 2575);
FORCEPROP 2 LAST CDS_LIB pure_quanta
J 0
(-2175 2525);
DISPLAY INVISIBLE (-2175 2525);
FORCEPROP 1 LAST PATH I85
J 0
(-2125 2675);
DISPLAY 0.978723 (-2125 2675);
PAINT WHITE (-2125 2675);
DISPLAY INVISIBLE (-2125 2675);
FORCEPROP 1 LAST PART_NUMBER CH4102K6E00
J 0
(-2125 2375);
DISPLAY 0.978723 (-2125 2375);
DISPLAY INVISIBLE (-2125 2375);
FORCEADD Q_CAP..1
(-2450 2525);
FORCEPROP 1 LAST LOCATION C253
J 0
(-2400 2625);
DISPLAY 0.978723 (-2400 2625);
PAINT WHITE (-2400 2625);
FORCEPROP 0 LAST $SEC 1
J 0
(-2400 2675);
DISPLAY 0.680851 (-2400 2675);
PAINT MONO (-2400 2675);
DISPLAY INVISIBLE (-2400 2675);
FORCEPROP 0 LAST CDS_SEC 1
J 0
(-2400 2675);
DISPLAY 0.680851 (-2400 2675);
DISPLAY INVISIBLE (-2400 2675);
FORCEPROP 1 LASTPIN (-2450 2625) $PN 1
J 0
(-2440 2605);
DISPLAY 0.787234 (-2440 2605);
PAINT MONO (-2440 2605);
FORCEPROP 1 LASTPIN (-2450 2425) $PN 2
J 0
(-2440 2405);
DISPLAY 0.787234 (-2440 2405);
PAINT MONO (-2440 2405);
FORCEPROP 1 LAST VALUE 0.1UF
J 0
(-2400 2575);
DISPLAY 0.638298 (-2400 2575);
FORCEPROP 1 LAST TOLERANCE 10%
J 0
(-2400 2475);
DISPLAY 0.638298 (-2400 2475);
FORCEPROP 1 LAST VOLTAGE 10V
J 0
(-2400 2525);
DISPLAY 0.638298 (-2400 2525);
FORCEPROP 1 LAST MATERIAL X7S
J 0
(-2400 2425);
DISPLAY 0.638298 (-2400 2425);
FORCEPROP 1 LAST PACK_TYPE C0201
J 0
(-2400 2375);
DISPLAY 0.638298 (-2400 2375);
FORCEPROP 2 LAST CDS_LIB pure_quanta
J 0
(-2450 2525);
DISPLAY INVISIBLE (-2450 2525);
FORCEPROP 1 LAST PATH I86
J 0
(-2400 2675);
DISPLAY 0.978723 (-2400 2675);
PAINT WHITE (-2400 2675);
DISPLAY INVISIBLE (-2400 2675);
FORCEPROP 1 LAST PART_NUMBER CH4102K6E00
J 0
(-2400 2375);
DISPLAY 0.978723 (-2400 2375);
DISPLAY INVISIBLE (-2400 2375);
FORCEADD Q_CAP..1
(-2700 2525);
FORCEPROP 1 LAST LOCATION C228
J 0
(-2650 2625);
DISPLAY 0.978723 (-2650 2625);
PAINT WHITE (-2650 2625);
FORCEPROP 0 LAST $SEC 1
J 0
(-2650 2675);
DISPLAY 0.680851 (-2650 2675);
PAINT MONO (-2650 2675);
DISPLAY INVISIBLE (-2650 2675);
FORCEPROP 0 LAST CDS_SEC 1
J 0
(-2650 2675);
DISPLAY 0.680851 (-2650 2675);
DISPLAY INVISIBLE (-2650 2675);
FORCEPROP 1 LASTPIN (-2700 2625) $PN 1
J 0
(-2690 2605);
DISPLAY 0.787234 (-2690 2605);
PAINT MONO (-2690 2605);
FORCEPROP 1 LASTPIN (-2700 2425) $PN 2
J 0
(-2690 2405);
DISPLAY 0.787234 (-2690 2405);
PAINT MONO (-2690 2405);
FORCEPROP 1 LAST PACK_TYPE C0201
J 0
(-2650 2375);
DISPLAY 0.638298 (-2650 2375);
FORCEPROP 1 LAST MATERIAL X7S
J 0
(-2650 2425);
DISPLAY 0.638298 (-2650 2425);
FORCEPROP 1 LAST VALUE 0.1UF
J 0
(-2650 2575);
DISPLAY 0.638298 (-2650 2575);
FORCEPROP 1 LAST VOLTAGE 10V
J 0
(-2650 2525);
DISPLAY 0.638298 (-2650 2525);
FORCEPROP 1 LAST TOLERANCE 10%
J 0
(-2650 2475);
DISPLAY 0.638298 (-2650 2475);
FORCEPROP 2 LAST CDS_LIB pure_quanta
J 0
(-2700 2525);
DISPLAY INVISIBLE (-2700 2525);
FORCEPROP 1 LAST PATH I87
J 0
(-2650 2675);
DISPLAY 0.978723 (-2650 2675);
PAINT WHITE (-2650 2675);
DISPLAY INVISIBLE (-2650 2675);
FORCEPROP 1 LAST PART_NUMBER CH4102K6E00
J 0
(-2650 2375);
DISPLAY 0.978723 (-2650 2375);
DISPLAY INVISIBLE (-2650 2375);
FORCEADD UNIVERSAL_GND..1
(-1650 2100);
FORCEPROP 3 LASTPIN (-1650 2150) SIG_NAME GND\g
J 0
(-1640 2160);
DISPLAY 0.659574 (-1640 2160);
PAINT MONO (-1640 2160);
DISPLAY INVISIBLE (-1640 2160);
FORCEPROP 2 LAST CDS_LIB pure_quanta_power
J 0
(-1650 2100);
DISPLAY INVISIBLE (-1650 2100);
FORCEPROP 1 LAST HDL_POWER GND
J 1
(-1625 2025);
DISPLAY 0.872340 (-1625 2025);
PAINT GREEN (-1625 2025);
DISPLAY INVISIBLE (-1625 2025);
FORCEPROP 1 LAST PATH I88
J 0
(-1575 2100);
DISPLAY 0.872340 (-1575 2100);
PAINT AQUA (-1575 2100);
DISPLAY INVISIBLE (-1575 2100);
FORCEADD VCC_CORE..1
(-3425 1950);
FORCEPROP 3 LASTPIN (-3425 1900) SIG_NAME P0V9_CPU1_RT0_2A_2D\g
J 0
(-3415 1910);
DISPLAY 0.659574 (-3415 1910);
PAINT MONO (-3415 1910);
DISPLAY INVISIBLE (-3415 1910);
FORCEPROP 1 LAST HDL_POWER P0V9_CPU1_RT0_2A_2D
J 1
(-3425 2000);
DISPLAY 0.617021 (-3425 2000);
PAINT GREEN (-3425 2000);
FORCEPROP 2 LAST CDS_LIB pure_quanta_power
J 0
(-3425 1950);
DISPLAY INVISIBLE (-3425 1950);
FORCEPROP 1 LAST PATH I89
J 0
(-3375 1975);
DISPLAY 0.872340 (-3375 1975);
PAINT AQUA (-3375 1975);
DISPLAY INVISIBLE (-3375 1975);
FORCEADD Q_CAP..1
(-6425 4475);
FORCEPROP 1 LAST LOCATION C126
J 0
(-6375 4575);
DISPLAY 0.808511 (-6375 4575);
PAINT WHITE (-6375 4575);
FORCEPROP 0 LAST $SEC 1
J 0
(-6375 4625);
DISPLAY 0.680851 (-6375 4625);
PAINT MONO (-6375 4625);
DISPLAY INVISIBLE (-6375 4625);
FORCEPROP 0 LAST CDS_SEC 1
J 0
(-6375 4625);
DISPLAY 0.680851 (-6375 4625);
DISPLAY INVISIBLE (-6375 4625);
FORCEPROP 1 LASTPIN (-6425 4575) $PN 1
J 0
(-6415 4555);
DISPLAY 0.787234 (-6415 4555);
PAINT MONO (-6415 4555);
FORCEPROP 1 LASTPIN (-6425 4375) $PN 2
J 0
(-6415 4355);
DISPLAY 0.787234 (-6415 4355);
PAINT MONO (-6415 4355);
FORCEPROP 1 LAST TOLERANCE 20%
J 0
(-6375 4425);
DISPLAY 0.510638 (-6375 4425);
FORCEPROP 1 LAST VOLTAGE 4V
J 0
(-6375 4475);
DISPLAY 0.510638 (-6375 4475);
FORCEPROP 1 LAST MATERIAL X6S
J 0
(-6375 4375);
DISPLAY 0.510638 (-6375 4375);
FORCEPROP 1 LAST PACK_TYPE 0201
J 0
(-6375 4325);
DISPLAY 0.510638 (-6375 4325);
FORCEPROP 1 LAST VALUE 1UF
J 0
(-6375 4525);
DISPLAY 0.510638 (-6375 4525);
FORCEPROP 2 LAST CDS_LIB pure_quanta
J 0
(-6425 4475);
DISPLAY INVISIBLE (-6425 4475);
FORCEPROP 1 LAST PATH I9
J 0
(-6375 4625);
DISPLAY 0.978723 (-6375 4625);
PAINT WHITE (-6375 4625);
DISPLAY INVISIBLE (-6375 4625);
FORCEPROP 1 LAST PART_NUMBER CH-10KMEE00
J 0
(-6375 4325);
DISPLAY 0.510638 (-6375 4325);
DISPLAY INVISIBLE (-6375 4325);
FORCEADD UNIVERSAL_GND..1
(-2600 1100);
FORCEPROP 3 LASTPIN (-2600 1150) SIG_NAME GND\g
J 0
(-2590 1160);
DISPLAY 0.659574 (-2590 1160);
PAINT MONO (-2590 1160);
DISPLAY INVISIBLE (-2590 1160);
FORCEPROP 2 LAST CDS_LIB pure_quanta_power
J 0
(-2600 1100);
DISPLAY INVISIBLE (-2600 1100);
FORCEPROP 1 LAST HDL_POWER GND
J 1
(-2575 1025);
DISPLAY 0.872340 (-2575 1025);
PAINT GREEN (-2575 1025);
DISPLAY INVISIBLE (-2575 1025);
FORCEPROP 1 LAST PATH I91
J 0
(-2525 1100);
DISPLAY 0.872340 (-2525 1100);
PAINT AQUA (-2525 1100);
DISPLAY INVISIBLE (-2525 1100);
FORCEADD Q_CAP..1
(-2750 1425);
FORCEPROP 1 LAST LOCATION C198
J 0
(-2700 1525);
DISPLAY 0.978723 (-2700 1525);
PAINT WHITE (-2700 1525);
FORCEPROP 0 LAST $SEC 1
J 0
(-2700 1575);
DISPLAY 0.680851 (-2700 1575);
PAINT MONO (-2700 1575);
DISPLAY INVISIBLE (-2700 1575);
FORCEPROP 0 LAST CDS_SEC 1
J 0
(-2700 1575);
DISPLAY 0.680851 (-2700 1575);
DISPLAY INVISIBLE (-2700 1575);
FORCEPROP 1 LASTPIN (-2750 1525) $PN 1
J 0
(-2740 1505);
DISPLAY 0.787234 (-2740 1505);
PAINT MONO (-2740 1505);
FORCEPROP 1 LASTPIN (-2750 1325) $PN 2
J 0
(-2740 1305);
DISPLAY 0.787234 (-2740 1305);
PAINT MONO (-2740 1305);
FORCEPROP 1 LAST TOLERANCE 10%
J 0
(-2700 1375);
DISPLAY 0.638298 (-2700 1375);
FORCEPROP 1 LAST MATERIAL X7S
J 0
(-2700 1325);
DISPLAY 0.638298 (-2700 1325);
FORCEPROP 1 LAST VALUE 0.1UF
J 0
(-2700 1475);
DISPLAY 0.638298 (-2700 1475);
FORCEPROP 1 LAST PACK_TYPE C0201
J 0
(-2700 1275);
DISPLAY 0.638298 (-2700 1275);
FORCEPROP 1 LAST VOLTAGE 10V
J 0
(-2700 1425);
DISPLAY 0.638298 (-2700 1425);
FORCEPROP 2 LAST CDS_LIB pure_quanta
J 0
(-2750 1425);
DISPLAY INVISIBLE (-2750 1425);
FORCEPROP 1 LAST PATH I92
J 0
(-2700 1575);
DISPLAY 0.978723 (-2700 1575);
PAINT WHITE (-2700 1575);
DISPLAY INVISIBLE (-2700 1575);
FORCEPROP 1 LAST PART_NUMBER CH4102K6E00
J 0
(-2700 1275);
DISPLAY 0.978723 (-2700 1275);
DISPLAY INVISIBLE (-2700 1275);
FORCEADD Q_CAP..1
(-3050 1425);
FORCEPROP 1 LAST LOCATION C191
J 0
(-3000 1525);
DISPLAY 0.978723 (-3000 1525);
PAINT WHITE (-3000 1525);
FORCEPROP 0 LAST $SEC 1
J 0
(-3000 1575);
DISPLAY 0.680851 (-3000 1575);
PAINT MONO (-3000 1575);
DISPLAY INVISIBLE (-3000 1575);
FORCEPROP 0 LAST CDS_SEC 1
J 0
(-3000 1575);
DISPLAY 0.680851 (-3000 1575);
DISPLAY INVISIBLE (-3000 1575);
FORCEPROP 1 LASTPIN (-3050 1525) $PN 1
J 0
(-3040 1505);
DISPLAY 0.787234 (-3040 1505);
PAINT MONO (-3040 1505);
FORCEPROP 1 LASTPIN (-3050 1325) $PN 2
J 0
(-3040 1305);
DISPLAY 0.787234 (-3040 1305);
PAINT MONO (-3040 1305);
FORCEPROP 1 LAST VALUE 0.1UF
J 0
(-3000 1475);
DISPLAY 0.638298 (-3000 1475);
FORCEPROP 1 LAST VOLTAGE 10V
J 0
(-3000 1425);
DISPLAY 0.638298 (-3000 1425);
FORCEPROP 1 LAST PACK_TYPE C0201
J 0
(-3000 1275);
DISPLAY 0.638298 (-3000 1275);
FORCEPROP 1 LAST MATERIAL X7S
J 0
(-3000 1325);
DISPLAY 0.638298 (-3000 1325);
FORCEPROP 1 LAST TOLERANCE 10%
J 0
(-3000 1375);
DISPLAY 0.638298 (-3000 1375);
FORCEPROP 2 LAST CDS_LIB pure_quanta
J 0
(-3050 1425);
DISPLAY INVISIBLE (-3050 1425);
FORCEPROP 1 LAST PATH I93
J 0
(-3000 1575);
DISPLAY 0.978723 (-3000 1575);
PAINT WHITE (-3000 1575);
DISPLAY INVISIBLE (-3000 1575);
FORCEPROP 1 LAST PART_NUMBER CH4102K6E00
J 0
(-3000 1275);
DISPLAY 0.978723 (-3000 1275);
DISPLAY INVISIBLE (-3000 1275);
FORCEADD Q_RES..1
(-4200 2775);
FORCEPROP 1 LAST LOCATION R6705
J 0
(-4250 2825);
DISPLAY 0.978723 (-4250 2825);
FORCEPROP 0 LAST $SEC 1
J 0
(-4250 2875);
DISPLAY 0.680851 (-4250 2875);
PAINT MONO (-4250 2875);
DISPLAY INVISIBLE (-4250 2875);
FORCEPROP 0 LAST CDS_SEC 1
J 0
(-4250 2875);
DISPLAY 0.680851 (-4250 2875);
DISPLAY INVISIBLE (-4250 2875);
FORCEPROP 1 LASTPIN (-4300 2775) $PN 1
J 0
(-4288 2787);
DISPLAY 0.787234 (-4288 2787);
PAINT MONO (-4288 2787);
FORCEPROP 1 LASTPIN (-4100 2775) $PN 2
J 0
(-4138 2787);
DISPLAY 0.787234 (-4138 2787);
PAINT MONO (-4138 2787);
FORCEPROP 1 LAST PACK_TYPE 0603LF
J 0
(-3950 2625);
DISPLAY 0.978723 (-3950 2625);
FORCEPROP 1 LAST WATTAGE 1/4W
J 2
(-4225 2625);
DISPLAY 0.978723 (-4225 2625);
FORCEPROP 1 LAST TOLERANCE 5%
J 0
(-4200 2675);
DISPLAY 0.978723 (-4200 2675);
FORCEPROP 1 LAST VALUE 0
J 2
(-4225 2675);
DISPLAY 0.978723 (-4225 2675);
FORCEPROP 1 LAST MATERIAL CHIP
J 0
(-4200 2625);
DISPLAY 0.978723 (-4200 2625);
FORCEPROP 2 LAST CDS_LIB pure_quanta
J 0
(-4200 2775);
DISPLAY INVISIBLE (-4200 2775);
FORCEPROP 1 LAST PATH I95
J 0
(-4250 2925);
DISPLAY 0.978723 (-4250 2925);
PAINT WHITE (-4250 2925);
DISPLAY INVISIBLE (-4250 2925);
FORCEPROP 1 LAST PART_NUMBER CS00006J900
J 0
(-4425 2550);
DISPLAY 0.978723 (-4425 2550);
DISPLAY INVISIBLE (-4425 2550);
FORCEADD Q_RES..2
R 2
(-4575 3050);
FORCEPROP 1 LAST LOCATION R6704
J 2
(-4620 3175);
DISPLAY 0.978723 (-4620 3175);
FORCEPROP 0 LAST $SEC 1
J 0
(-4600 3225);
DISPLAY 0.680851 (-4600 3225);
PAINT MONO (-4600 3225);
DISPLAY INVISIBLE (-4600 3225);
FORCEPROP 0 LAST CDS_SEC 1
J 0
(-4600 3225);
DISPLAY 0.680851 (-4600 3225);
DISPLAY INVISIBLE (-4600 3225);
FORCEPROP 1 LASTPIN (-4575 3150) $PN 1
J 2
(-4580 3112);
DISPLAY 0.787234 (-4580 3112);
PAINT MONO (-4580 3112);
FORCEPROP 1 LASTPIN (-4575 2950) $PN 2
J 2
(-4580 2960);
DISPLAY 0.787234 (-4580 2960);
PAINT MONO (-4580 2960);
FORCEPROP 1 LAST MATERIAL EMPTY
J 2
(-4615 2975);
DISPLAY 0.978723 (-4615 2975);
FORCEPROP 1 LAST PACK_TYPE 0603LF
J 2
(-4615 2875);
DISPLAY 0.978723 (-4615 2875);
FORCEPROP 1 LAST VALUE 0
J 2
(-4620 3125);
DISPLAY 0.978723 (-4620 3125);
FORCEPROP 1 LAST WATTAGE 1/4W
J 2
(-4615 3025);
DISPLAY 0.978723 (-4615 3025);
FORCEPROP 1 LAST TOLERANCE 5%
J 2
(-4620 3075);
DISPLAY 0.978723 (-4620 3075);
FORCEPROP 2 LAST CDS_LIB pure_quanta
J 2
(-4575 3050);
DISPLAY INVISIBLE (-4575 3050);
FORCEPROP 1 LAST PATH I96
J 2
(-4625 3225);
DISPLAY 0.978723 (-4625 3225);
PAINT WHITE (-4625 3225);
DISPLAY INVISIBLE (-4625 3225);
FORCEPROP 1 LAST PART_NUMBER CS00006J900
J 2
(-4615 2925);
DISPLAY 0.978723 (-4615 2925);
DISPLAY INVISIBLE (-4615 2925);
FORCEADD Q_INDUCTOR..1
R 3
(-8500 4400);
FORCEPROP 1 LAST LOCATION L27
R 1
J 2
(-8660 4525);
DISPLAY 0.723404 (-8660 4525);
PAINT GREEN (-8660 4525);
FORCEPROP 0 LAST $SEC 1
R 1
J 0
(-8475 4525);
DISPLAY 0.680851 (-8475 4525);
PAINT MONO (-8475 4525);
DISPLAY INVISIBLE (-8475 4525);
FORCEPROP 0 LAST CDS_SEC 1
R 1
J 0
(-8475 4525);
DISPLAY 0.680851 (-8475 4525);
DISPLAY INVISIBLE (-8475 4525);
FORCEPROP 0 LASTPIN (-8475 4500) $PN 1
R 1
J 0
(-8485 4510);
DISPLAY 0.680851 (-8485 4510);
PAINT MONO (-8485 4510);
FORCEPROP 0 LASTPIN (-8475 4300) $PN 2
R 1
J 2
(-8485 4290);
DISPLAY 0.680851 (-8485 4290);
PAINT MONO (-8485 4290);
FORCEPROP 1 LAST MATERIAL IND
R 1
J 2
(-8555 4525);
DISPLAY 0.574468 (-8555 4525);
PAINT GREEN (-8555 4525);
FORCEPROP 2 LAST VALUE BLM15PD121SN1D/1300MA
R 1
J 2
(-8750 4525);
DISPLAY 0.553191 (-8750 4525);
FORCEPROP 2 LAST PACK_TYPE SMLF
R 1
J 2
(-8700 4525);
DISPLAY 0.553191 (-8700 4525);
FORCEPROP 1 LAST NEEDS_NO_SIZE TRUE
R 1
J 2
(-8500 4400);
DISPLAY 0.468085 (-8500 4400);
PAINT GREEN (-8500 4400);
DISPLAY INVISIBLE (-8500 4400);
FORCEPROP 2 LAST CDS_LIB pure_quanta
J 0
(-8500 4400);
DISPLAY INVISIBLE (-8500 4400);
FORCEPROP 1 LAST PATH I97
R 1
J 2
(-8555 4325);
DISPLAY 0.723404 (-8555 4325);
PAINT GREEN (-8555 4325);
DISPLAY INVISIBLE (-8555 4325);
FORCEPROP 1 LAST PART_NUMBER CX5PD121000
R 1
J 2
(-8600 4525);
DISPLAY 0.574468 (-8600 4525);
PAINT GREEN (-8600 4525);
DISPLAY INVISIBLE (-8600 4525);
FORCEADD Q_RES..2
(-8375 4375);
FORCEPROP 1 LAST LOCATION R6701
J 0
(-8330 4500);
DISPLAY 0.808511 (-8330 4500);
FORCEPROP 0 LAST $SEC 1
J 0
(-8325 4550);
DISPLAY 0.680851 (-8325 4550);
PAINT MONO (-8325 4550);
DISPLAY INVISIBLE (-8325 4550);
FORCEPROP 0 LAST CDS_SEC 1
J 0
(-8325 4550);
DISPLAY 0.680851 (-8325 4550);
DISPLAY INVISIBLE (-8325 4550);
FORCEPROP 1 LASTPIN (-8375 4475) $PN 1
J 0
(-8370 4437);
DISPLAY 0.787234 (-8370 4437);
PAINT MONO (-8370 4437);
FORCEPROP 1 LASTPIN (-8375 4275) $PN 2
J 0
(-8370 4285);
DISPLAY 0.787234 (-8370 4285);
PAINT MONO (-8370 4285);
FORCEPROP 1 LAST VALUE 0
J 0
(-8330 4450);
DISPLAY 0.638298 (-8330 4450);
FORCEPROP 1 LAST PACK_TYPE 0402LF
J 0
(-8335 4200);
DISPLAY 0.638298 (-8335 4200);
FORCEPROP 1 LAST MATERIAL EMPTY
J 0
(-8335 4300);
DISPLAY 0.638298 (-8335 4300);
PAINT RED (-8335 4300);
FORCEPROP 1 LAST TOLERANCE 5%
J 0
(-8330 4400);
DISPLAY 0.638298 (-8330 4400);
FORCEPROP 1 LAST WATTAGE 1/16W
J 0
(-8335 4350);
DISPLAY 0.638298 (-8335 4350);
FORCEPROP 2 LAST CDS_LIB pure_quanta
J 0
(-8375 4375);
DISPLAY INVISIBLE (-8375 4375);
FORCEPROP 1 LAST PATH I98
J 0
(-8325 4550);
DISPLAY 0.978723 (-8325 4550);
PAINT WHITE (-8325 4550);
DISPLAY INVISIBLE (-8325 4550);
FORCEPROP 1 LAST PART_NUMBER CS00002JB13
J 0
(-8335 4250);
DISPLAY 0.638298 (-8335 4250);
DISPLAY INVISIBLE (-8335 4250);
FORCEADD Q_CAP..1
(-3300 1425);
FORCEPROP 1 LAST LOCATION C187
J 0
(-3250 1525);
DISPLAY 0.978723 (-3250 1525);
PAINT WHITE (-3250 1525);
FORCEPROP 0 LAST $SEC 1
J 0
(-3250 1575);
DISPLAY 0.680851 (-3250 1575);
PAINT MONO (-3250 1575);
DISPLAY INVISIBLE (-3250 1575);
FORCEPROP 0 LAST CDS_SEC 1
J 0
(-3250 1575);
DISPLAY 0.680851 (-3250 1575);
DISPLAY INVISIBLE (-3250 1575);
FORCEPROP 1 LASTPIN (-3300 1525) $PN 1
J 0
(-3290 1505);
DISPLAY 0.787234 (-3290 1505);
PAINT MONO (-3290 1505);
FORCEPROP 1 LASTPIN (-3300 1325) $PN 2
J 0
(-3290 1305);
DISPLAY 0.787234 (-3290 1305);
PAINT MONO (-3290 1305);
FORCEPROP 1 LAST VALUE 1UF
J 0
(-3250 1475);
DISPLAY 0.510638 (-3250 1475);
FORCEPROP 1 LAST PACK_TYPE 0201
J 0
(-3250 1275);
DISPLAY 0.510638 (-3250 1275);
FORCEPROP 1 LAST MATERIAL X6S
J 0
(-3250 1325);
DISPLAY 0.510638 (-3250 1325);
FORCEPROP 1 LAST TOLERANCE 20%
J 0
(-3250 1375);
DISPLAY 0.510638 (-3250 1375);
FORCEPROP 1 LAST VOLTAGE 4V
J 0
(-3250 1425);
DISPLAY 0.510638 (-3250 1425);
FORCEPROP 2 LAST CDS_LIB pure_quanta
J 0
(-3300 1425);
DISPLAY INVISIBLE (-3300 1425);
FORCEPROP 1 LAST PATH I99
J 0
(-3250 1575);
DISPLAY 0.978723 (-3250 1575);
PAINT WHITE (-3250 1575);
DISPLAY INVISIBLE (-3250 1575);
FORCEPROP 1 LAST PART_NUMBER CH-10KMEE00
J 0
(-3250 1275);
DISPLAY 0.510638 (-3250 1275);
DISPLAY INVISIBLE (-3250 1275);
FORCEADD QUANTA_TITLE_BLOCK_C..1
(0 0);
FORCEPROP 0 LAST CDS_CON_LAST_MODIFIED Thu Sep 14 16:13:01 2023
J 0
(-1885 15);
DISPLAY INVISIBLE (-1885 15);
FORCEPROP 1 LAST CUSTOM_TXT_CDS <CON_LAST_MODIFIED>
J 0
(-1885 15);
DISPLAY 0.978723 (-1885 15);
FORCEPROP 2 LAST CUSTOM_TXT_CDS <XR_PAGE_TITLE>
J 0
(-7890 5250);
DISPLAY 0.638298 (-7890 5250);
PAINT PINK (-7890 5250);
DISPLAY INVISIBLE (-7890 5250);
FORCEPROP 1 LAST CUSTOM_TXT_CDS <NAME_2>
J 0
(-3175 50);
FORCEPROP 1 LAST CUSTOM_TXT_CDS <NAME_1>
J 0
(-3175 175);
FORCEPROP 1 LAST CUSTOM_TXT_CDS <Q_NUMBER>
J 0
(-1403 103);
DISPLAY 1.212766 (-1403 103);
FORCEPROP 1 LAST CUSTOM_TXT_CDS <Q_PROJ>
J 0
(-2382 102);
DISPLAY 1.212766 (-2382 102);
FORCEPROP 1 LAST CUSTOM_TXT_CDS <Q_REV>
J 0
(-184 103);
DISPLAY 1.212766 (-184 103);
FORCEPROP 1 LAST CUSTOM_TXT_CDS <CON_PAGE_NUM> OF <CON_TOTAL_PAGES>
J 0
(-446 18);
DISPLAY 0.978723 (-446 18);
FORCEPROP 1 LAST Q_TITLE RETIMER_CPU1_P0 DECAPS (8)
J 0
(-9366 26);
DISPLAY 2.446809 (-9366 26);
PAINT GREEN (-9366 26);
FORCEPROP 2 LAST PAGE_BORDER TRUE
J 0
(-7890 5250);
DISPLAY 0.638298 (-7890 5250);
PAINT PINK (-7890 5250);
DISPLAY INVISIBLE (-7890 5250);
FORCEPROP 1 LAST CDS_LMAN_SYM_OUTLINE -9475,6775,100,-125
J 0
(0 0);
DISPLAY 0.468085 (0 0);
PAINT GREEN (0 0);
DISPLAY INVISIBLE (0 0);
FORCEPROP 2 LAST CDS_LIB pure_quanta
J 0
(0 0);
DISPLAY INVISIBLE (0 0);
FORCEPROP 2 LAST CDS_XR_PAGE_TITLE CR-324 : @T6G_MB_LIB.T6G(SCH_1):PAGE324
J 0
(-7890 5250);
DISPLAY 0.638298 (-7890 5250);
PAINT PINK (-7890 5250);
DISPLAY INVISIBLE (-7890 5250);
FORCEPROP 1 LAST Q_DEPT BU9
J 1
(-3763 49);
DISPLAY 1.957447 (-3763 49);
PAINT GREEN (-3763 49);
DISPLAY INVISIBLE (-3763 49);
FORCEPROP 1 LAST COMMENT_BODY TRUE
J 0
(12 -13);
DISPLAY 0.978723 (12 -13);
PAINT GREEN (12 -13);
DISPLAY INVISIBLE (12 -13);
FORCEADD DNS..2
(-4625 3025);
PAINT RED (-4625 3025);
FORCEPROP 2 LAST CDS_LIB mstr_misc
J 0
(-4625 3025);
DISPLAY INVISIBLE (-4625 3025);
FORCEPROP 1 LAST COMMENT_BODY TRUE
J 0
(-4625 3025);
DISPLAY INVISIBLE (-4625 3025);
FORCEADD CAD_NOTE..1
(-5375 2725);
FORCEPROP 0 LAST S1 R6704 AND R6705 COLAY
J 0
(-5500 2600);
DISPLAY 0.808511 (-5500 2600);
PAINT WHITE (-5500 2600);
FORCEPROP 2 LAST CDS_LIB pure_quanta_power
J 0
(-5375 2725);
DISPLAY INVISIBLE (-5375 2725);
FORCEPROP 1 LAST COMMENT_BODY TRUE
J 0
(-5350 2825);
DISPLAY 0.978723 (-5350 2825);
DISPLAY INVISIBLE (-5350 2825);
FORCEADD DNS..2
(-7950 3825);
PAINT RED (-7950 3825);
FORCEPROP 2 LAST CDS_LIB mstr_misc
J 0
(-7950 3825);
DISPLAY INVISIBLE (-7950 3825);
FORCEPROP 1 LAST COMMENT_BODY TRUE
J 0
(-7950 3825);
DISPLAY INVISIBLE (-7950 3825);
FORCEADD CAD_NOTE..1
(-8425 3225);
FORCEPROP 0 LAST S1 L27/R6701 COLAY WITH R6702/R6703
J 0
(-8550 3100);
DISPLAY 0.808511 (-8550 3100);
PAINT WHITE (-8550 3100);
FORCEPROP 2 LAST CDS_LIB pure_quanta_power
J 0
(-8425 3225);
DISPLAY INVISIBLE (-8425 3225);
FORCEPROP 1 LAST COMMENT_BODY TRUE
J 0
(-8400 3325);
DISPLAY 0.978723 (-8400 3325);
DISPLAY INVISIBLE (-8400 3325);
FORCEADD DNS..2
(-7950 4000);
PAINT RED (-7950 4000);
FORCEPROP 2 LAST CDS_LIB mstr_misc
J 0
(-7950 4000);
DISPLAY INVISIBLE (-7950 4000);
FORCEPROP 1 LAST COMMENT_BODY TRUE
J 0
(-7950 4000);
DISPLAY INVISIBLE (-7950 4000);
FORCEADD DNS..2
(-8300 4375);
PAINT RED (-8300 4375);
FORCEPROP 2 LAST CDS_LIB mstr_misc
J 0
(-8300 4375);
DISPLAY INVISIBLE (-8300 4375);
FORCEPROP 1 LAST COMMENT_BODY TRUE
J 0
(-8300 4375);
DISPLAY INVISIBLE (-8300 4375);
WIRE 16 -1 (-8425 4725)(-8425 4575);
WIRE 16 -1 (-8425 4725)(-8150 4725);
WIRE 16 -1 (-8425 5450)(-8425 4725);
WIRE 16 -1 (-8425 4575)(-8375 4575);
WIRE 16 -1 (-8425 4575)(-8475 4575);
WIRE 16 -1 (-8475 4575)(-8475 4500);
WIRE 16 -1 (-8375 4575)(-8375 4475);
WIRE 16 -1 (-7325 5450)(-8425 5450);
WIRE 16 -1 (-8425 5525)(-8425 5450);
WIRE 16 -1 (-7325 5450)(-7075 5450);
WIRE 16 -1 (-7325 5450)(-7325 5400);
WIRE 16 -1 (-7075 5450)(-6825 5450);
WIRE 16 -1 (-7075 5450)(-7075 5400);
WIRE 16 -1 (-6825 5450)(-6575 5450);
WIRE 16 -1 (-6825 5450)(-6825 5375);
WIRE 16 -1 (-6575 5450)(-6575 5375);
WIRE 16 -1 (-6575 5175)(-6575 5050);
WIRE 16 -1 (-6650 5050)(-6575 5050);
WIRE 16 -1 (-6825 5050)(-6650 5050);
WIRE 16 -1 (-6825 5175)(-6825 5050);
WIRE 16 -1 (-7075 5050)(-6825 5050);
WIRE 16 -1 (-7075 5200)(-7075 5050);
WIRE 16 -1 (-7325 5050)(-7075 5050);
WIRE 16 -1 (-7325 5200)(-7325 5050);
WIRE 16 -1 (-5425 4725)(-5425 4575);
WIRE 16 -1 (-5425 4725)(-5700 4725);
WIRE 16 -1 (-5700 4725)(-5950 4725);
WIRE 16 -1 (-5700 4725)(-5700 4575);
WIRE 16 -1 (-5950 4725)(-5950 4575);
WIRE 16 -1 (-5950 4725)(-6200 4725);
WIRE 16 -1 (-6425 4725)(-6200 4725);
WIRE 16 -1 (-6200 4725)(-6200 4575);
WIRE 16 -1 (-6425 4725)(-6625 4725);
WIRE 16 -1 (-6425 4725)(-6425 4575);
WIRE 16 -1 (-6625 4725)(-6625 4575);
WIRE 16 -1 (-6625 4725)(-6850 4725);
WIRE 16 -1 (-7050 4725)(-6850 4725);
WIRE 16 -1 (-6850 4725)(-6850 4575);
WIRE 16 -1 (-7050 4725)(-7050 4575);
WIRE 16 -1 (-7050 4725)(-7250 4725);
WIRE 16 -1 (-7475 4725)(-7250 4725);
WIRE 16 -1 (-7250 4725)(-7250 4575);
WIRE 16 -1 (-7475 4725)(-7575 4725);
WIRE 16 -1 (-7475 4725)(-7475 4575);
WIRE 16 -1 (-7575 4900)(-7575 4725);
WIRE 16 -1 (-7575 4725)(-7950 4725);
WIRE 16 -1 (-7575 3950)(-7575 4725);
WIRE 16 -1 (-7675 3950)(-7575 3950);
WIRE 16 -1 (-7675 3950)(-7675 3850);
WIRE 16 -1 (-7675 4050)(-7675 3950);
WIRE 16 -1 (-7875 4050)(-7675 4050);
WIRE 16 -1 (-7875 3850)(-7675 3850);
WIRE 16 -1 (-5425 4375)(-5425 4275);
WIRE 16 -1 (-5700 4275)(-5425 4275);
WIRE 16 -1 (-5700 4375)(-5700 4275);
WIRE 16 -1 (-5950 4275)(-5700 4275);
WIRE 16 -1 (-5950 4375)(-5950 4275);
WIRE 16 -1 (-6200 4275)(-5950 4275);
WIRE 16 -1 (-6200 4375)(-6200 4275);
WIRE 16 -1 (-6425 4275)(-6200 4275);
WIRE 16 -1 (-6625 4275)(-6425 4275);
WIRE 16 -1 (-6425 4375)(-6425 4275);
WIRE 16 -1 (-6425 4275)(-6425 4200);
WIRE 16 -1 (-6625 4375)(-6625 4275);
WIRE 16 -1 (-6850 4275)(-6625 4275);
WIRE 16 -1 (-6850 4375)(-6850 4275);
WIRE 16 -1 (-7050 4275)(-6850 4275);
WIRE 16 -1 (-7050 4375)(-7050 4275);
WIRE 16 -1 (-7250 4275)(-7050 4275);
WIRE 16 -1 (-7250 4375)(-7250 4275);
WIRE 16 -1 (-7475 4275)(-7250 4275);
WIRE 16 -1 (-7475 4375)(-7475 4275);
WIRE 16 -1 (-750 2775)(-750 2650);
WIRE 16 -1 (-1050 2775)(-750 2775);
WIRE 16 -1 (-1050 2650)(-1050 2775);
WIRE 16 -1 (-1350 2775)(-1050 2775);
WIRE 16 -1 (-1350 2650)(-1350 2775);
WIRE 16 -1 (-1650 2775)(-1350 2775);
WIRE 16 -1 (-1650 2625)(-1650 2775);
WIRE 16 -1 (-1650 2775)(-1900 2775);
WIRE 16 -1 (-1900 2625)(-1900 2775);
WIRE 16 -1 (-2175 2775)(-1900 2775);
WIRE 16 -1 (-2175 2625)(-2175 2775);
WIRE 16 -1 (-2450 2775)(-2175 2775);
WIRE 16 -1 (-2450 2625)(-2450 2775);
WIRE 16 -1 (-2700 2775)(-2450 2775);
WIRE 16 -1 (-2700 2625)(-2700 2775);
WIRE 16 -1 (-2950 2775)(-2700 2775);
WIRE 16 -1 (-2950 2775)(-2950 2625);
WIRE 16 -1 (-3175 2775)(-2950 2775);
WIRE 16 -1 (-3175 2775)(-3175 2625);
WIRE 16 -1 (-3475 2775)(-3175 2775);
WIRE 16 -1 (-3475 2775)(-3475 2625);
WIRE 16 -1 (-3925 2775)(-3475 2775);
WIRE 16 -1 (-3925 3450)(-3925 2775);
WIRE 16 -1 (-3925 2775)(-4100 2775);
WIRE 16 -1 (-3925 4075)(-3925 3450);
WIRE 16 -1 (-3925 3450)(-3750 3450);
WIRE 16 -1 (-3750 3450)(-3525 3450);
WIRE 16 -1 (-3750 3450)(-3750 3325);
WIRE 16 -1 (-3925 4725)(-3925 4075);
WIRE 16 -1 (-3925 4075)(-3750 4075);
WIRE 16 -1 (-3750 4075)(-3525 4075);
WIRE 16 -1 (-3750 3950)(-3750 4075);
WIRE 16 -1 (-3925 4725)(-3750 4725);
WIRE 16 -1 (-4000 4725)(-3925 4725);
WIRE 16 -1 (-3525 3450)(-3275 3450);
WIRE 16 -1 (-3525 3450)(-3525 3325);
WIRE 16 -1 (-3275 3450)(-3050 3450);
WIRE 16 -1 (-3275 3450)(-3275 3325);
WIRE 16 -1 (-3750 4725)(-3525 4725);
WIRE 16 -1 (-3750 5075)(-3750 4725);
WIRE 16 -1 (-3750 4725)(-3750 4575);
WIRE 16 -1 (-3525 4075)(-3300 4075);
WIRE 16 -1 (-3525 3950)(-3525 4075);
WIRE 16 -1 (-3300 4075)(-3075 4075);
WIRE 16 -1 (-3300 3950)(-3300 4075);
WIRE 16 -1 (-3300 4725)(-3525 4725);
WIRE 16 -1 (-3525 4725)(-3525 4575);
WIRE 16 -1 (-3050 3450)(-2800 3450);
WIRE 16 -1 (-3050 3450)(-3050 3325);
WIRE 16 -1 (-2800 3450)(-2575 3450);
WIRE 16 -1 (-2800 3450)(-2800 3325);
WIRE 16 -1 (-3075 4725)(-3300 4725);
WIRE 16 -1 (-3300 4725)(-3300 4575);
WIRE 16 -1 (-3075 4075)(-2825 4075);
WIRE 16 -1 (-3075 3950)(-3075 4075);
WIRE 16 -1 (-2825 4075)(-2600 4075);
WIRE 16 -1 (-2825 3950)(-2825 4075);
WIRE 16 -1 (-2825 4725)(-3075 4725);
WIRE 16 -1 (-3075 4725)(-3075 4575);
WIRE 16 -1 (-2575 3450)(-2350 3450);
WIRE 16 -1 (-2575 3450)(-2575 3300);
WIRE 16 -1 (-2125 3450)(-2350 3450);
WIRE 16 -1 (-2350 3300)(-2350 3450);
WIRE 16 -1 (-2600 4725)(-2825 4725);
WIRE 16 -1 (-2825 4725)(-2825 4575);
WIRE 16 -1 (-2600 4075)(-2375 4075);
WIRE 16 -1 (-2600 3950)(-2600 4075);
WIRE 16 -1 (-2375 4075)(-2150 4075);
WIRE 16 -1 (-2375 3950)(-2375 4075);
WIRE 16 -1 (-2375 4725)(-2600 4725);
WIRE 16 -1 (-2600 4725)(-2600 4575);
WIRE 16 -1 (-2125 3450)(-1875 3450);
WIRE 16 -1 (-2125 3300)(-2125 3450);
WIRE 16 -1 (-1875 3450)(-1875 3300);
WIRE 16 -1 (-2150 4725)(-2375 4725);
WIRE 16 -1 (-2375 4725)(-2375 4575);
WIRE 16 -1 (-2150 4075)(-1925 4075);
WIRE 16 -1 (-2150 3950)(-2150 4075);
WIRE 16 -1 (-1675 4075)(-1925 4075);
WIRE 16 -1 (-1925 3950)(-1925 4075);
WIRE 16 -1 (-1850 4725)(-2150 4725);
WIRE 16 -1 (-2150 4725)(-2150 4575);
WIRE 16 -1 (-1850 4725)(-1550 4725);
WIRE 16 -1 (-1850 4725)(-1850 4575);
WIRE 16 -1 (-1675 4075)(-1675 3950);
WIRE 16 -1 (-1550 4725)(-1550 4575);
WIRE 16 -1 (-3750 3125)(-3750 2900);
WIRE 16 -1 (-3750 2900)(-3525 2900);
WIRE 16 -1 (-3525 3125)(-3525 2900);
WIRE 16 -1 (-3525 2900)(-3275 2900);
WIRE 16 -1 (-3275 2900)(-3050 2900);
WIRE 16 -1 (-3275 3125)(-3275 2900);
WIRE 16 -1 (-3050 3125)(-3050 2900);
WIRE 16 -1 (-3050 2900)(-2800 2900);
WIRE 16 -1 (-2800 3125)(-2800 2900);
WIRE 16 -1 (-2800 2900)(-2575 2900);
WIRE 16 -1 (-2575 3100)(-2575 2900);
WIRE 16 -1 (-2575 2900)(-2350 2900);
WIRE 16 -1 (-2350 3100)(-2350 2900);
WIRE 16 -1 (-2125 2900)(-2350 2900);
WIRE 16 -1 (-2125 2900)(-1875 2900);
WIRE 16 -1 (-2125 3100)(-2125 2900);
WIRE 16 -1 (-1875 3100)(-1875 2900);
WIRE 16 -1 (-1150 2900)(-1875 2900);
WIRE 16 -1 (-1150 3625)(-1150 2900);
WIRE 16 -1 (-1150 2900)(-1150 2850);
WIRE 16 -1 (-1150 4225)(-1150 3625);
WIRE 16 -1 (-1150 3625)(-1675 3625);
WIRE 16 -1 (-1675 3750)(-1675 3625);
WIRE 16 -1 (-1675 3625)(-1925 3625);
WIRE 16 -1 (-1150 4225)(-1550 4225);
WIRE 16 -1 (-1550 4375)(-1550 4225);
WIRE 16 -1 (-1550 4225)(-1850 4225);
WIRE 16 -1 (-1925 3750)(-1925 3625);
WIRE 16 -1 (-2150 3625)(-1925 3625);
WIRE 16 -1 (-2150 3750)(-2150 3625);
WIRE 16 -1 (-2375 3625)(-2150 3625);
WIRE 16 -1 (-1850 4375)(-1850 4225);
WIRE 16 -1 (-1850 4225)(-2150 4225);
WIRE 16 -1 (-2150 4375)(-2150 4225);
WIRE 16 -1 (-2150 4225)(-2375 4225);
WIRE 16 -1 (-2375 3750)(-2375 3625);
WIRE 16 -1 (-2600 3625)(-2375 3625);
WIRE 16 -1 (-2600 3750)(-2600 3625);
WIRE 16 -1 (-2825 3625)(-2600 3625);
WIRE 16 -1 (-2375 4375)(-2375 4225);
WIRE 16 -1 (-2375 4225)(-2600 4225);
WIRE 16 -1 (-2600 4375)(-2600 4225);
WIRE 16 -1 (-2600 4225)(-2825 4225);
WIRE 16 -1 (-2825 3750)(-2825 3625);
WIRE 16 -1 (-3075 3625)(-2825 3625);
WIRE 16 -1 (-3075 3750)(-3075 3625);
WIRE 16 -1 (-3300 3625)(-3075 3625);
WIRE 16 -1 (-2825 4375)(-2825 4225);
WIRE 16 -1 (-2825 4225)(-3075 4225);
WIRE 16 -1 (-3075 4375)(-3075 4225);
WIRE 16 -1 (-3300 4225)(-3075 4225);
WIRE 16 -1 (-3300 3750)(-3300 3625);
WIRE 16 -1 (-3525 3625)(-3300 3625);
WIRE 16 -1 (-3525 3750)(-3525 3625);
WIRE 16 -1 (-3750 3625)(-3525 3625);
WIRE 16 -1 (-3300 4375)(-3300 4225);
WIRE 16 -1 (-3525 4225)(-3300 4225);
WIRE 16 -1 (-3525 4375)(-3525 4225);
WIRE 16 -1 (-3750 4225)(-3525 4225);
WIRE 16 -1 (-3750 3750)(-3750 3625);
WIRE 16 -1 (-3750 4375)(-3750 4225);
WIRE 16 -1 (-1400 5975)(-1400 5800);
WIRE 16 -1 (-1675 5975)(-1400 5975);
WIRE 16 -1 (-1675 5975)(-1675 5800);
WIRE 16 -1 (-1925 5975)(-1675 5975);
WIRE 16 -1 (-1925 5800)(-1925 5975);
WIRE 16 -1 (-2200 5975)(-1925 5975);
WIRE 16 -1 (-2200 5975)(-2200 5800);
WIRE 16 -1 (-2500 5975)(-2200 5975);
WIRE 16 -1 (-2500 5975)(-2500 5825);
WIRE 16 -1 (-2800 5975)(-2500 5975);
WIRE 16 -1 (-2800 5975)(-2800 5825);
WIRE 16 -1 (-3100 5975)(-2800 5975);
WIRE 16 -1 (-3100 5975)(-3100 5825);
WIRE 16 -1 (-3425 5975)(-3100 5975);
WIRE 16 -1 (-3425 5975)(-3425 5850);
WIRE 16 -1 (-3700 5975)(-3425 5975);
WIRE 16 -1 (-3700 5975)(-3700 5850);
WIRE 16 -1 (-4575 5975)(-3700 5975);
WIRE 16 -1 (-4575 6200)(-4575 5975);
WIRE 16 -1 (-4575 4725)(-4575 5975);
WIRE 16 -1 (-4200 4725)(-4575 4725);
WIRE 16 -1 (-4575 4725)(-4575 3150);
WIRE 16 -1 (-1400 5600)(-1400 5425);
WIRE 16 -1 (-1400 5425)(-1475 5425);
WIRE 16 -1 (-1475 5425)(-1675 5425);
WIRE 16 -1 (-1475 5425)(-1475 5350);
WIRE 16 -1 (-1675 5600)(-1675 5425);
WIRE 16 -1 (-1925 5425)(-1675 5425);
WIRE 16 -1 (-1925 5600)(-1925 5425);
WIRE 16 -1 (-2200 5425)(-1925 5425);
WIRE 16 -1 (-2200 5600)(-2200 5425);
WIRE 16 -1 (-2200 5425)(-2500 5425);
WIRE 16 -1 (-2500 5625)(-2500 5425);
WIRE 16 -1 (-2800 5425)(-2500 5425);
WIRE 16 -1 (-2800 5625)(-2800 5425);
WIRE 16 -1 (-3100 5425)(-2800 5425);
WIRE 16 -1 (-3100 5625)(-3100 5425);
WIRE 16 -1 (-3425 5425)(-3100 5425);
WIRE 16 -1 (-3425 5650)(-3425 5425);
WIRE 16 -1 (-3700 5425)(-3425 5425);
WIRE 16 -1 (-3700 5650)(-3700 5425);
WIRE 16 -1 (-3475 2425)(-3475 2300);
WIRE 16 -1 (-3475 2300)(-3175 2300);
WIRE 16 -1 (-3175 2300)(-2950 2300);
WIRE 16 -1 (-3175 2425)(-3175 2300);
WIRE 16 -1 (-2950 2300)(-2700 2300);
WIRE 16 -1 (-2950 2425)(-2950 2300);
WIRE 16 -1 (-2700 2300)(-2450 2300);
WIRE 16 -1 (-2700 2425)(-2700 2300);
WIRE 16 -1 (-2450 2300)(-2175 2300);
WIRE 16 -1 (-2450 2425)(-2450 2300);
WIRE 16 -1 (-1900 2300)(-2175 2300);
WIRE 16 -1 (-2175 2425)(-2175 2300);
WIRE 16 -1 (-1900 2300)(-1650 2300);
WIRE 16 -1 (-1900 2425)(-1900 2300);
WIRE 16 -1 (-1350 2300)(-1650 2300);
WIRE 16 -1 (-1650 2425)(-1650 2300);
WIRE 16 -1 (-1650 2300)(-1650 2150);
WIRE 16 -1 (-1050 2300)(-1350 2300);
WIRE 16 -1 (-1350 2450)(-1350 2300);
WIRE 16 -1 (-750 2300)(-1050 2300);
WIRE 16 -1 (-1050 2450)(-1050 2300);
WIRE 16 -1 (-750 2450)(-750 2300);
WIRE 16 -1 (-2500 1325)(-2500 1200);
WIRE 16 -1 (-2500 1200)(-2600 1200);
WIRE 16 -1 (-2750 1200)(-2600 1200);
WIRE 16 -1 (-2600 1200)(-2600 1150);
WIRE 16 -1 (-2750 1325)(-2750 1200);
WIRE 16 -1 (-3050 1200)(-2750 1200);
WIRE 16 -1 (-3050 1325)(-3050 1200);
WIRE 16 -1 (-3300 1200)(-3050 1200);
WIRE 16 -1 (-3300 1325)(-3300 1200);
WIRE 16 -1 (-2500 1525)(-2500 1675);
WIRE 16 -1 (-2500 1675)(-2750 1675);
WIRE 16 -1 (-2750 1675)(-3050 1675);
WIRE 16 -1 (-2750 1525)(-2750 1675);
WIRE 16 -1 (-3050 1675)(-3050 1525);
WIRE 16 -1 (-3050 1675)(-3300 1675);
WIRE 16 -1 (-3300 1675)(-3425 1675);
WIRE 16 -1 (-3300 1675)(-3300 1525);
WIRE 16 -1 (-3425 1900)(-3425 1675);
WIRE 16 -1 (-4575 1675)(-3425 1675);
WIRE 16 -1 (-4575 1675)(-4575 2775);
WIRE 16 -1 (-4575 2775)(-4300 2775);
WIRE 16 -1 (-4575 2950)(-4575 2775);
WIRE 16 -1 (-7050 3625)(-6775 3625);
WIRE 16 -1 (-7050 3500)(-7050 3625);
WIRE 16 -1 (-7050 3625)(-7175 3625);
WIRE 16 -1 (-6775 3625)(-6775 3475);
WIRE 16 -1 (-8425 3625)(-7175 3625);
WIRE 16 -1 (-7175 3625)(-7175 3725);
WIRE 16 -1 (-8425 3625)(-8425 3950);
WIRE 16 -1 (-8425 3950)(-8425 4125);
WIRE 16 -1 (-8425 3950)(-8325 3950);
WIRE 16 -1 (-8325 4050)(-8325 3950);
WIRE 16 -1 (-8325 3950)(-8325 3850);
WIRE 16 -1 (-8425 4125)(-8375 4125);
WIRE 16 -1 (-8475 4125)(-8425 4125);
WIRE 16 -1 (-8475 4125)(-8475 4300);
WIRE 16 -1 (-8375 4125)(-8375 4275);
WIRE 16 -1 (-8325 3850)(-8075 3850);
WIRE 16 -1 (-8075 4050)(-8325 4050);
WIRE 16 -1 (-7050 3300)(-7050 3125);
WIRE 16 -1 (-7050 3125)(-6775 3125);
WIRE 16 -1 (-6775 3275)(-6775 3125);
WIRE 16 -1 (-6775 3125)(-6775 3025);
DOT 1 (-8425 4725);
DOT 1 (-8425 4575);
DOT 1 (-8325 3950);
DOT 1 (-8425 4125);
DOT 1 (-8425 5450);
DOT 1 (-7675 3950);
DOT 1 (-7175 3625);
DOT 1 (-6775 3125);
DOT 1 (-7050 3625);
DOT 1 (-4575 2775);
DOT 1 (-7250 4275);
DOT 1 (-7575 4725);
DOT 1 (-7475 4725);
DOT 1 (-7250 4725);
DOT 1 (-7325 5450);
DOT 1 (-7050 4275);
DOT 1 (-6850 4275);
DOT 1 (-7050 4725);
DOT 1 (-7075 5050);
DOT 1 (-6850 4725);
DOT 1 (-6825 5050);
DOT 1 (-6425 4275);
DOT 1 (-6625 4725);
DOT 1 (-6825 5450);
DOT 1 (-4575 4725);
DOT 1 (-4575 5975);
DOT 1 (-3425 1675);
DOT 1 (-2750 1200);
DOT 1 (-2600 1200);
DOT 1 (-3050 1675);
DOT 1 (-2750 1675);
DOT 1 (-3925 2775);
DOT 1 (-3175 2300);
DOT 1 (-3475 2775);
DOT 1 (-3525 2900);
DOT 1 (-3175 2775);
DOT 1 (-3275 2900);
DOT 1 (-3925 3450);
DOT 1 (-3925 4075);
DOT 1 (-3750 4075);
DOT 1 (-3525 3450);
DOT 1 (-3275 3450);
DOT 1 (-3525 4075);
DOT 1 (-3300 3625);
DOT 1 (-3075 3625);
DOT 1 (-2950 2300);
DOT 1 (-3050 3450);
DOT 1 (-2600 3625);
DOT 1 (-2375 3625);
DOT 1 (-1150 2900);
DOT 1 (-1925 3625);
DOT 1 (-1150 3625);
DOT 1 (-3525 4225);
DOT 1 (-3075 4225);
DOT 1 (-3525 4725);
DOT 1 (-3075 4725);
DOT 1 (-3300 4725);
DOT 1 (-3700 5975);
DOT 1 (-3425 5425);
DOT 1 (-3425 5975);
DOT 1 (-3100 5975);
DOT 1 (-2825 4225);
DOT 1 (-2375 4725);
DOT 1 (-2150 4725);
DOT 1 (-2800 5975);
DOT 1 (-2500 5425);
DOT 1 (-2200 5425);
DOT 1 (-2500 5975);
DOT 1 (-1675 5425);
DOT 1 (-1925 5975);
DOT 1 (-1675 5975);
DOT 1 (-1475 5425);
DOT 1 (-8425 3950);
DOT 1 (-7075 5450);
DOT 1 (-6425 4725);
DOT 1 (-6200 4725);
DOT 1 (-5950 4725);
DOT 1 (-5700 4725);
DOT 1 (-5700 4275);
DOT 1 (-5950 4275);
DOT 1 (-6625 4275);
DOT 1 (-2800 5425);
DOT 1 (-3100 5425);
DOT 1 (-2200 5975);
DOT 1 (-1925 5425);
DOT 1 (-3925 4725);
DOT 1 (-6200 4275);
DOT 1 (-1850 4725);
DOT 1 (-3750 4725);
DOT 1 (-1550 4225);
DOT 1 (-2825 3625);
DOT 1 (-2575 3450);
DOT 1 (-2175 2775);
DOT 1 (-2825 4725);
DOT 1 (-2600 4725);
DOT 1 (-2600 4225);
DOT 1 (-3300 4225);
DOT 1 (-3300 4075);
DOT 1 (-3075 4075);
DOT 1 (-2600 4075);
DOT 1 (-2375 4225);
DOT 1 (-2825 4075);
DOT 1 (-2375 4075);
DOT 1 (-2150 4225);
DOT 1 (-2150 4075);
DOT 1 (-1925 4075);
DOT 1 (-3750 3450);
DOT 1 (-1675 3625);
DOT 1 (-2700 2775);
DOT 1 (-2950 2775);
DOT 1 (-2450 2775);
DOT 1 (-2800 3450);
DOT 1 (-2800 2900);
DOT 1 (-3525 3625);
DOT 1 (-2150 3625);
DOT 1 (-2450 2300);
DOT 1 (-2175 2300);
DOT 1 (-3050 2900);
DOT 1 (-1900 2300);
DOT 1 (-1900 2775);
DOT 1 (-1875 2900);
DOT 1 (-2125 3450);
DOT 1 (-3050 1200);
DOT 1 (-3300 1675);
DOT 1 (-2700 2300);
DOT 1 (-1850 4225);
DOT 1 (-1650 2775);
DOT 1 (-1650 2300);
DOT 1 (-2125 2900);
DOT 1 (-2350 2900);
DOT 1 (-2575 2900);
DOT 1 (-2350 3450);
DOT 1 (-1050 2775);
DOT 1 (-1050 2300);
DOT 1 (-1350 2775);
DOT 1 (-1350 2300);
QUIT
